G04 ================== begin FILE IDENTIFICATION RECORD ==================*
G04 Layout Name:  13130-1b.brd*
G04 Film Name:    NOTICE*
G04 File Format:  Gerber RS274X*
G04 File Origin:  Cadence Allegro 16.5-S037*
G04 Origin Date:  Thu Nov 13 17:26:37 2014*
G04 *
G04 Layer:  MANUFACTURING/THERMAL*
G04 *
G04 Offset:    (0.00 0.00)*
G04 Mirror:    No*
G04 Mode:      Positive*
G04 Rotation:  0*
G04 FullContactRelief:  No*
G04 UndefLineWidth:     6.00*
G04 ================== end FILE IDENTIFICATION RECORD ====================*
%FSLAX35Y35*MOIN*%
%IR0*IPPOS*OFA0.00000B0.00000*MIA0B0*SFA1.00000B1.00000*%
%ADD10C,.02*%
%ADD11C,.015*%
%ADD12C,.006*%
G75*
%LPD*%
G75*
G36*
G01X-150182Y391982D02*
G02X-171728Y413528I7501J29047D01*
G01X-176868Y413529D01*
G03X-150181Y386842I34187J7500D01*
G01X-150182Y391982D01*
G37*
G36*
G01X-171728Y428529D02*
G02X-150182Y450076I29047J-7500D01*
G01X-150181Y455216D01*
G03X-176868Y428528I7500J-34187D01*
G01X-171728Y428529D01*
G37*
G36*
G01X-95311Y-58090D02*
G02X-122870Y-20533I11812J37557D01*
G01Y-4785D01*
X-116965D01*
Y-20533D01*
G03X-95311Y-51844I33464J0D01*
G01Y-58090D01*
G37*
G36*
G01X-122870Y34585D02*
Y50333D01*
G02X-95311Y87890I39371J0D01*
G01Y81644D01*
G03X-116965Y50333I11810J-31311D01*
G01Y34585D01*
X-122870D01*
G37*
G36*
G01X-113634Y413528D02*
G02X-135181Y391982I-29047J7501D01*
G01X-135182Y386842D01*
G03X-108494Y413529I-7499J34187D01*
G01X-113634Y413528D01*
G37*
G36*
G01X-135181Y450076D02*
G02X-113634Y428529I-7500J-29047D01*
G01X-108494Y428528D01*
G03X-135182Y455216I-34187J-7499D01*
G01X-135181Y450076D01*
G37*
G36*
G01X-71689Y-58090D02*
Y-51844D01*
G03X-50035Y-20533I-11810J31311D01*
G01Y-4785D01*
X-44130D01*
Y-20533D01*
G02X-71689Y-58090I-39371J0D01*
G37*
G36*
G01X-50035Y34585D02*
Y50333D01*
G03X-71689Y81644I-33464J0D01*
G01Y87890D01*
G02X-44130Y50333I-11812J-37557D01*
G01Y34585D01*
X-50035D01*
G37*
G54D10*
G01X-315200Y-238600D02*
Y-227975D01*
X-314783Y-226934D01*
X-313950Y-226308D01*
X-312700Y-226100D01*
X-311450Y-226517D01*
X-310825Y-227558D01*
G01X-313325Y-231100D02*
X-317492D01*
G01X-298450Y-238600D02*
X-299700Y-238392D01*
X-300950Y-237559D01*
X-301784Y-236100D01*
X-302200Y-234433D01*
X-301784Y-232767D01*
X-300950Y-231308D01*
X-299700Y-230475D01*
X-298450Y-230267D01*
X-297200Y-230475D01*
X-295950Y-231308D01*
X-295117Y-232767D01*
X-294908Y-234433D01*
X-295117Y-236100D01*
X-295950Y-237559D01*
X-297200Y-238392D01*
X-298450Y-238600D01*
G01X-282950D02*
Y-226100D01*
G01X-267450Y-238600D02*
Y-226100D01*
G01X-251950Y-238600D02*
X-253200Y-238392D01*
X-254450Y-237559D01*
X-255284Y-236100D01*
X-255700Y-234433D01*
X-255284Y-232767D01*
X-254450Y-231308D01*
X-253200Y-230475D01*
X-251950Y-230267D01*
X-250700Y-230475D01*
X-249450Y-231308D01*
X-248617Y-232767D01*
X-248408Y-234433D01*
X-248617Y-236100D01*
X-249450Y-237559D01*
X-250700Y-238392D01*
X-251950Y-238600D01*
G01X-241659Y-230267D02*
X-239158Y-238600D01*
X-236450Y-230267D01*
X-233742Y-238600D01*
X-231241Y-230267D01*
G01X-208367Y-241725D02*
X-206908Y-242558D01*
X-205242Y-242767D01*
X-203783Y-242558D01*
X-202533Y-241517D01*
X-201700Y-240058D01*
Y-230267D01*
G01Y-231933D02*
X-202533Y-231100D01*
X-203783Y-230475D01*
X-205242Y-230267D01*
X-206908Y-230683D01*
X-207950Y-231517D01*
X-208784Y-232975D01*
X-209200Y-234433D01*
X-208992Y-235684D01*
X-208158Y-237142D01*
X-206908Y-238183D01*
X-205242Y-238600D01*
X-203992Y-238392D01*
X-202533Y-237559D01*
X-201700Y-236725D01*
G01X-193075Y-232975D02*
X-186408D01*
X-187033Y-231517D01*
X-188075Y-230683D01*
X-189533Y-230267D01*
X-190992Y-230475D01*
X-192242Y-231100D01*
X-193075Y-232558D01*
X-193492Y-233809D01*
Y-235058D01*
X-193075Y-236308D01*
X-192033Y-237559D01*
X-190783Y-238392D01*
X-189325Y-238600D01*
X-187867Y-238183D01*
X-186408Y-236934D01*
G01X-177367Y-238600D02*
Y-230267D01*
G01Y-231933D02*
X-176325Y-231100D01*
X-175283Y-230475D01*
X-173825Y-230267D01*
X-172783Y-230475D01*
X-171533Y-231100D01*
G01X-162700Y-238600D02*
Y-226100D01*
G01Y-232350D02*
X-161658Y-231100D01*
X-160408Y-230475D01*
X-159158Y-230267D01*
X-157283Y-230683D01*
X-156033Y-231517D01*
X-155200Y-232975D01*
Y-234642D01*
X-155617Y-236308D01*
X-156450Y-237559D01*
X-157908Y-238392D01*
X-159158Y-238600D01*
X-160408Y-238392D01*
X-161658Y-237767D01*
X-162700Y-236725D01*
G01X-146575Y-232975D02*
X-139908D01*
X-140533Y-231517D01*
X-141575Y-230683D01*
X-143033Y-230267D01*
X-144492Y-230475D01*
X-145742Y-231100D01*
X-146575Y-232558D01*
X-146992Y-233809D01*
Y-235058D01*
X-146575Y-236308D01*
X-145533Y-237559D01*
X-144283Y-238392D01*
X-142825Y-238600D01*
X-141367Y-238183D01*
X-139908Y-236934D01*
G01X-130867Y-238600D02*
Y-230267D01*
G01Y-231933D02*
X-129825Y-231100D01*
X-128783Y-230475D01*
X-127325Y-230267D01*
X-126283Y-230475D01*
X-125033Y-231100D01*
G01X-93200Y-226100D02*
Y-238600D01*
G01Y-236725D02*
X-94033Y-237767D01*
X-95283Y-238392D01*
X-96742Y-238600D01*
X-98408Y-238183D01*
X-99658Y-237142D01*
X-100492Y-235892D01*
X-100700Y-234433D01*
X-100492Y-232975D01*
X-99658Y-231725D01*
X-98408Y-230683D01*
X-96742Y-230267D01*
X-95283Y-230475D01*
X-94242Y-230892D01*
X-93200Y-231725D01*
G01X-84575Y-232975D02*
X-77908D01*
X-78533Y-231517D01*
X-79575Y-230683D01*
X-81033Y-230267D01*
X-82492Y-230475D01*
X-83742Y-231100D01*
X-84575Y-232558D01*
X-84992Y-233809D01*
Y-235058D01*
X-84575Y-236308D01*
X-83533Y-237559D01*
X-82283Y-238392D01*
X-80825Y-238600D01*
X-79367Y-238183D01*
X-77908Y-236934D01*
G01X-69075Y-237142D02*
X-68033Y-237975D01*
X-66575Y-238600D01*
X-65325D01*
X-64075Y-238183D01*
X-63242Y-237559D01*
X-62825Y-236725D01*
X-63033Y-235475D01*
X-63867Y-234850D01*
X-67617Y-233600D01*
X-68450Y-232142D01*
X-68033Y-231100D01*
X-67200Y-230475D01*
X-65950Y-230267D01*
X-64700Y-230475D01*
X-63450Y-231100D01*
G01X-50450Y-230267D02*
Y-238600D01*
G01Y-226934D02*
X-50867Y-226725D01*
Y-226308D01*
X-50450Y-226100D01*
X-50033Y-226308D01*
Y-226725D01*
X-50450Y-226934D01*
G01X-37867Y-241725D02*
X-36408Y-242558D01*
X-34742Y-242767D01*
X-33283Y-242558D01*
X-32033Y-241517D01*
X-31200Y-240058D01*
Y-230267D01*
G01Y-231933D02*
X-32033Y-231100D01*
X-33283Y-230475D01*
X-34742Y-230267D01*
X-36408Y-230683D01*
X-37450Y-231517D01*
X-38284Y-232975D01*
X-38700Y-234433D01*
X-38492Y-235684D01*
X-37658Y-237142D01*
X-36408Y-238183D01*
X-34742Y-238600D01*
X-33492Y-238392D01*
X-32033Y-237559D01*
X-31200Y-236725D01*
G01X-22992Y-238600D02*
Y-230267D01*
G01Y-232350D02*
X-22158Y-231308D01*
X-20908Y-230475D01*
X-19242Y-230267D01*
X-17783Y-230475D01*
X-16533Y-231308D01*
X-15908Y-232767D01*
Y-238600D01*
G01X-317908Y-216900D02*
Y-204400D01*
X-309992D01*
G01X-312908Y-210442D02*
X-317908D01*
G01X-298450Y-216900D02*
X-299700Y-216692D01*
X-300950Y-215859D01*
X-301784Y-214400D01*
X-302200Y-212733D01*
X-301784Y-211067D01*
X-300950Y-209608D01*
X-299700Y-208775D01*
X-298450Y-208567D01*
X-297200Y-208775D01*
X-295950Y-209608D01*
X-295117Y-211067D01*
X-294908Y-212733D01*
X-295117Y-214400D01*
X-295950Y-215859D01*
X-297200Y-216692D01*
X-298450Y-216900D01*
G01X-285867D02*
Y-208567D01*
G01Y-210233D02*
X-284825Y-209400D01*
X-283783Y-208775D01*
X-282325Y-208567D01*
X-281283Y-208775D01*
X-280033Y-209400D01*
G01X-255908Y-206483D02*
X-254658Y-205234D01*
X-253200Y-204608D01*
X-251533Y-204400D01*
X-249450Y-204817D01*
X-247992Y-205858D01*
X-247575Y-207108D01*
X-247783Y-208359D01*
X-248617Y-209400D01*
X-252783Y-211483D01*
X-254658Y-212942D01*
X-255908Y-215025D01*
X-256325Y-216900D01*
X-247575D01*
G01X-236867D02*
X-236450Y-214192D01*
X-235825Y-211900D01*
X-234992Y-209817D01*
X-233950Y-207525D01*
X-232283Y-204400D01*
X-240617D01*
G01X-218450Y-216900D02*
Y-204400D01*
X-226159Y-213358D01*
X-215741D01*
G01X-209825Y-216900D02*
X-201075Y-204400D01*
G01X-209825D02*
X-201075Y-216900D01*
G01X-177367Y-220025D02*
X-175908Y-220858D01*
X-174242Y-221067D01*
X-172783Y-220858D01*
X-171533Y-219817D01*
X-170700Y-218358D01*
Y-208567D01*
G01Y-210233D02*
X-171533Y-209400D01*
X-172783Y-208775D01*
X-174242Y-208567D01*
X-175908Y-208983D01*
X-176950Y-209817D01*
X-177784Y-211275D01*
X-178200Y-212733D01*
X-177992Y-213984D01*
X-177158Y-215442D01*
X-175908Y-216483D01*
X-174242Y-216900D01*
X-172992Y-216692D01*
X-171533Y-215859D01*
X-170700Y-215025D01*
G01X-162075Y-211275D02*
X-155408D01*
X-156033Y-209817D01*
X-157075Y-208983D01*
X-158533Y-208567D01*
X-159992Y-208775D01*
X-161242Y-209400D01*
X-162075Y-210858D01*
X-162492Y-212109D01*
Y-213358D01*
X-162075Y-214608D01*
X-161033Y-215859D01*
X-159783Y-216692D01*
X-158325Y-216900D01*
X-156867Y-216483D01*
X-155408Y-215234D01*
G01X-146367Y-216900D02*
Y-208567D01*
G01Y-210233D02*
X-145325Y-209400D01*
X-144283Y-208775D01*
X-142825Y-208567D01*
X-141783Y-208775D01*
X-140533Y-209400D01*
G01X-131700Y-216900D02*
Y-204400D01*
G01Y-210650D02*
X-130658Y-209400D01*
X-129408Y-208775D01*
X-128158Y-208567D01*
X-126283Y-208983D01*
X-125033Y-209817D01*
X-124200Y-211275D01*
Y-212942D01*
X-124617Y-214608D01*
X-125450Y-215859D01*
X-126908Y-216692D01*
X-128158Y-216900D01*
X-129408Y-216692D01*
X-130658Y-216067D01*
X-131700Y-215025D01*
G01X-115575Y-211275D02*
X-108908D01*
X-109533Y-209817D01*
X-110575Y-208983D01*
X-112033Y-208567D01*
X-113492Y-208775D01*
X-114742Y-209400D01*
X-115575Y-210858D01*
X-115992Y-212109D01*
Y-213358D01*
X-115575Y-214608D01*
X-114533Y-215859D01*
X-113283Y-216692D01*
X-111825Y-216900D01*
X-110367Y-216483D01*
X-108908Y-215234D01*
G01X-99867Y-216900D02*
Y-208567D01*
G01Y-210233D02*
X-98825Y-209400D01*
X-97783Y-208775D01*
X-96325Y-208567D01*
X-95283Y-208775D01*
X-94033Y-209400D01*
G01X-67200Y-216900D02*
Y-206275D01*
X-66783Y-205234D01*
X-65950Y-204608D01*
X-64700Y-204400D01*
X-63450Y-204817D01*
X-62825Y-205858D01*
G01X-65325Y-209400D02*
X-69492D01*
G01X-50450Y-216900D02*
X-51700Y-216692D01*
X-52950Y-215859D01*
X-53784Y-214400D01*
X-54200Y-212733D01*
X-53784Y-211067D01*
X-52950Y-209608D01*
X-51700Y-208775D01*
X-50450Y-208567D01*
X-49200Y-208775D01*
X-47950Y-209608D01*
X-47117Y-211067D01*
X-46908Y-212733D01*
X-47117Y-214400D01*
X-47950Y-215859D01*
X-49200Y-216692D01*
X-50450Y-216900D01*
G01X-37867D02*
Y-208567D01*
G01Y-210233D02*
X-36825Y-209400D01*
X-35783Y-208775D01*
X-34325Y-208567D01*
X-33283Y-208775D01*
X-32033Y-209400D01*
G01X-25700Y-216900D02*
Y-208567D01*
G01Y-210858D02*
X-25075Y-209817D01*
X-24033Y-208983D01*
X-22575Y-208567D01*
X-21117Y-208983D01*
X-20075Y-209817D01*
X-19450Y-210858D01*
Y-216900D01*
G01Y-210858D02*
X-18825Y-209817D01*
X-17783Y-208983D01*
X-16325Y-208567D01*
X-14867Y-208983D01*
X-13825Y-209817D01*
X-13200Y-211067D01*
Y-216900D01*
G01X-200D02*
Y-208567D01*
G01Y-210025D02*
X-1033Y-209192D01*
X-2283Y-208775D01*
X-3742Y-208567D01*
X-5200Y-208983D01*
X-6450Y-209817D01*
X-7284Y-211067D01*
X-7700Y-212733D01*
X-7284Y-214400D01*
X-6450Y-215650D01*
X-5200Y-216483D01*
X-3742Y-216900D01*
X-2283Y-216692D01*
X-1033Y-216067D01*
X-200Y-215234D01*
G01X11550Y-204400D02*
Y-216900D01*
G01X8633Y-208567D02*
X14467D01*
G01X42550Y-204400D02*
Y-216900D01*
G01X39633Y-208567D02*
X45467D01*
G01X54508Y-216900D02*
Y-204400D01*
G01Y-210442D02*
X55550Y-209400D01*
X56592Y-208775D01*
X58258Y-208567D01*
X59508Y-208775D01*
X60967Y-209608D01*
X61592Y-210858D01*
Y-216900D01*
G01X70425Y-211275D02*
X77092D01*
X76467Y-209817D01*
X75425Y-208983D01*
X73967Y-208567D01*
X72508Y-208775D01*
X71258Y-209400D01*
X70425Y-210858D01*
X70008Y-212109D01*
Y-213358D01*
X70425Y-214608D01*
X71467Y-215859D01*
X72717Y-216692D01*
X74175Y-216900D01*
X75633Y-216483D01*
X77092Y-215234D01*
G01X86133Y-216900D02*
Y-208567D01*
G01Y-210233D02*
X87175Y-209400D01*
X88217Y-208775D01*
X89675Y-208567D01*
X90717Y-208775D01*
X91967Y-209400D01*
G01X98300Y-216900D02*
Y-208567D01*
G01Y-210858D02*
X98925Y-209817D01*
X99967Y-208983D01*
X101425Y-208567D01*
X102883Y-208983D01*
X103925Y-209817D01*
X104550Y-210858D01*
Y-216900D01*
G01Y-210858D02*
X105175Y-209817D01*
X106217Y-208983D01*
X107675Y-208567D01*
X109133Y-208983D01*
X110175Y-209817D01*
X110800Y-211067D01*
Y-216900D01*
G01X123800D02*
Y-208567D01*
G01Y-210025D02*
X122967Y-209192D01*
X121717Y-208775D01*
X120258Y-208567D01*
X118800Y-208983D01*
X117550Y-209817D01*
X116716Y-211067D01*
X116300Y-212733D01*
X116716Y-214400D01*
X117550Y-215650D01*
X118800Y-216483D01*
X120258Y-216900D01*
X121717Y-216692D01*
X122967Y-216067D01*
X123800Y-215234D01*
G01X135550Y-216900D02*
Y-204400D01*
G01X163633Y-216900D02*
Y-208567D01*
G01Y-210233D02*
X164675Y-209400D01*
X165717Y-208775D01*
X167175Y-208567D01*
X168217Y-208775D01*
X169467Y-209400D01*
G01X178925Y-211275D02*
X185592D01*
X184967Y-209817D01*
X183925Y-208983D01*
X182467Y-208567D01*
X181008Y-208775D01*
X179758Y-209400D01*
X178925Y-210858D01*
X178508Y-212109D01*
Y-213358D01*
X178925Y-214608D01*
X179967Y-215859D01*
X181217Y-216692D01*
X182675Y-216900D01*
X184133Y-216483D01*
X185592Y-215234D01*
G01X197550Y-216900D02*
Y-204400D01*
G01X213050Y-208567D02*
Y-216900D01*
G01Y-205234D02*
X212633Y-205025D01*
Y-204608D01*
X213050Y-204400D01*
X213467Y-204608D01*
Y-205025D01*
X213050Y-205234D01*
G01X225425Y-211275D02*
X232092D01*
X231467Y-209817D01*
X230425Y-208983D01*
X228967Y-208567D01*
X227508Y-208775D01*
X226258Y-209400D01*
X225425Y-210858D01*
X225008Y-212109D01*
Y-213358D01*
X225425Y-214608D01*
X226467Y-215859D01*
X227717Y-216692D01*
X229175Y-216900D01*
X230633Y-216483D01*
X232092Y-215234D01*
G01X242800Y-216900D02*
Y-206275D01*
X243217Y-205234D01*
X244050Y-204608D01*
X245300Y-204400D01*
X246550Y-204817D01*
X247175Y-205858D01*
G01X244675Y-209400D02*
X240508D01*
G01X-305600Y215300D02*
Y225925D01*
X-305183Y226966D01*
X-304350Y227592D01*
X-303100Y227800D01*
X-301850Y227383D01*
X-301225Y226342D01*
G01X-303725Y222800D02*
X-307892D01*
G01X-288850Y215300D02*
X-290100Y215508D01*
X-291350Y216341D01*
X-292184Y217800D01*
X-292600Y219467D01*
X-292184Y221133D01*
X-291350Y222592D01*
X-290100Y223425D01*
X-288850Y223633D01*
X-287600Y223425D01*
X-286350Y222592D01*
X-285517Y221133D01*
X-285308Y219467D01*
X-285517Y217800D01*
X-286350Y216341D01*
X-287600Y215508D01*
X-288850Y215300D01*
G01X-273350D02*
Y227800D01*
G01X-257850Y215300D02*
Y227800D01*
G01X-242350Y215300D02*
X-243600Y215508D01*
X-244850Y216341D01*
X-245684Y217800D01*
X-246100Y219467D01*
X-245684Y221133D01*
X-244850Y222592D01*
X-243600Y223425D01*
X-242350Y223633D01*
X-241100Y223425D01*
X-239850Y222592D01*
X-239017Y221133D01*
X-238808Y219467D01*
X-239017Y217800D01*
X-239850Y216341D01*
X-241100Y215508D01*
X-242350Y215300D01*
G01X-232059Y223633D02*
X-229558Y215300D01*
X-226850Y223633D01*
X-224142Y215300D01*
X-221641Y223633D01*
G01X-198767Y212175D02*
X-197308Y211342D01*
X-195642Y211133D01*
X-194183Y211342D01*
X-192933Y212383D01*
X-192100Y213842D01*
Y223633D01*
G01Y221967D02*
X-192933Y222800D01*
X-194183Y223425D01*
X-195642Y223633D01*
X-197308Y223217D01*
X-198350Y222383D01*
X-199184Y220925D01*
X-199600Y219467D01*
X-199392Y218216D01*
X-198558Y216758D01*
X-197308Y215717D01*
X-195642Y215300D01*
X-194392Y215508D01*
X-192933Y216341D01*
X-192100Y217175D01*
G01X-183475Y220925D02*
X-176808D01*
X-177433Y222383D01*
X-178475Y223217D01*
X-179933Y223633D01*
X-181392Y223425D01*
X-182642Y222800D01*
X-183475Y221342D01*
X-183892Y220091D01*
Y218842D01*
X-183475Y217592D01*
X-182433Y216341D01*
X-181183Y215508D01*
X-179725Y215300D01*
X-178267Y215717D01*
X-176808Y216966D01*
G01X-167767Y215300D02*
Y223633D01*
G01Y221967D02*
X-166725Y222800D01*
X-165683Y223425D01*
X-164225Y223633D01*
X-163183Y223425D01*
X-161933Y222800D01*
G01X-153100Y215300D02*
Y227800D01*
G01Y221550D02*
X-152058Y222800D01*
X-150808Y223425D01*
X-149558Y223633D01*
X-147683Y223217D01*
X-146433Y222383D01*
X-145600Y220925D01*
Y219258D01*
X-146017Y217592D01*
X-146850Y216341D01*
X-148308Y215508D01*
X-149558Y215300D01*
X-150808Y215508D01*
X-152058Y216133D01*
X-153100Y217175D01*
G01X-136975Y220925D02*
X-130308D01*
X-130933Y222383D01*
X-131975Y223217D01*
X-133433Y223633D01*
X-134892Y223425D01*
X-136142Y222800D01*
X-136975Y221342D01*
X-137392Y220091D01*
Y218842D01*
X-136975Y217592D01*
X-135933Y216341D01*
X-134683Y215508D01*
X-133225Y215300D01*
X-131767Y215717D01*
X-130308Y216966D01*
G01X-121267Y215300D02*
Y223633D01*
G01Y221967D02*
X-120225Y222800D01*
X-119183Y223425D01*
X-117725Y223633D01*
X-116683Y223425D01*
X-115433Y222800D01*
G01X-83600Y227800D02*
Y215300D01*
G01Y217175D02*
X-84433Y216133D01*
X-85683Y215508D01*
X-87142Y215300D01*
X-88808Y215717D01*
X-90058Y216758D01*
X-90892Y218008D01*
X-91100Y219467D01*
X-90892Y220925D01*
X-90058Y222175D01*
X-88808Y223217D01*
X-87142Y223633D01*
X-85683Y223425D01*
X-84642Y223008D01*
X-83600Y222175D01*
G01X-74975Y220925D02*
X-68308D01*
X-68933Y222383D01*
X-69975Y223217D01*
X-71433Y223633D01*
X-72892Y223425D01*
X-74142Y222800D01*
X-74975Y221342D01*
X-75392Y220091D01*
Y218842D01*
X-74975Y217592D01*
X-73933Y216341D01*
X-72683Y215508D01*
X-71225Y215300D01*
X-69767Y215717D01*
X-68308Y216966D01*
G01X-59475Y216758D02*
X-58433Y215925D01*
X-56975Y215300D01*
X-55725D01*
X-54475Y215717D01*
X-53642Y216341D01*
X-53225Y217175D01*
X-53433Y218425D01*
X-54267Y219050D01*
X-58017Y220300D01*
X-58850Y221758D01*
X-58433Y222800D01*
X-57600Y223425D01*
X-56350Y223633D01*
X-55100Y223425D01*
X-53850Y222800D01*
G01X-40850Y223633D02*
Y215300D01*
G01Y226966D02*
X-41267Y227175D01*
Y227592D01*
X-40850Y227800D01*
X-40433Y227592D01*
Y227175D01*
X-40850Y226966D01*
G01X-28267Y212175D02*
X-26808Y211342D01*
X-25142Y211133D01*
X-23683Y211342D01*
X-22433Y212383D01*
X-21600Y213842D01*
Y223633D01*
G01Y221967D02*
X-22433Y222800D01*
X-23683Y223425D01*
X-25142Y223633D01*
X-26808Y223217D01*
X-27850Y222383D01*
X-28684Y220925D01*
X-29100Y219467D01*
X-28892Y218216D01*
X-28058Y216758D01*
X-26808Y215717D01*
X-25142Y215300D01*
X-23892Y215508D01*
X-22433Y216341D01*
X-21600Y217175D01*
G01X-13392Y215300D02*
Y223633D01*
G01Y221550D02*
X-12558Y222592D01*
X-11308Y223425D01*
X-9642Y223633D01*
X-8183Y223425D01*
X-6933Y222592D01*
X-6308Y221133D01*
Y215300D01*
G01X-308308Y237000D02*
Y249500D01*
X-300392D01*
G01X-303308Y243458D02*
X-308308D01*
G01X-288850Y237000D02*
X-290100Y237208D01*
X-291350Y238041D01*
X-292184Y239500D01*
X-292600Y241167D01*
X-292184Y242833D01*
X-291350Y244292D01*
X-290100Y245125D01*
X-288850Y245333D01*
X-287600Y245125D01*
X-286350Y244292D01*
X-285517Y242833D01*
X-285308Y241167D01*
X-285517Y239500D01*
X-286350Y238041D01*
X-287600Y237208D01*
X-288850Y237000D01*
G01X-276267D02*
Y245333D01*
G01Y243667D02*
X-275225Y244500D01*
X-274183Y245125D01*
X-272725Y245333D01*
X-271683Y245125D01*
X-270433Y244500D01*
G01X-246308Y247417D02*
X-245058Y248666D01*
X-243600Y249292D01*
X-241933Y249500D01*
X-239850Y249083D01*
X-238392Y248042D01*
X-237975Y246792D01*
X-238183Y245541D01*
X-239017Y244500D01*
X-243183Y242417D01*
X-245058Y240958D01*
X-246308Y238875D01*
X-246725Y237000D01*
X-237975D01*
G01X-227267D02*
X-226850Y239708D01*
X-226225Y242000D01*
X-225392Y244083D01*
X-224350Y246375D01*
X-222683Y249500D01*
X-231017D01*
G01X-208850Y237000D02*
Y249500D01*
X-216559Y240542D01*
X-206141D01*
G01X-200225Y237000D02*
X-191475Y249500D01*
G01X-200225D02*
X-191475Y237000D01*
G01X-167767Y233875D02*
X-166308Y233042D01*
X-164642Y232833D01*
X-163183Y233042D01*
X-161933Y234083D01*
X-161100Y235542D01*
Y245333D01*
G01Y243667D02*
X-161933Y244500D01*
X-163183Y245125D01*
X-164642Y245333D01*
X-166308Y244917D01*
X-167350Y244083D01*
X-168184Y242625D01*
X-168600Y241167D01*
X-168392Y239916D01*
X-167558Y238458D01*
X-166308Y237417D01*
X-164642Y237000D01*
X-163392Y237208D01*
X-161933Y238041D01*
X-161100Y238875D01*
G01X-152475Y242625D02*
X-145808D01*
X-146433Y244083D01*
X-147475Y244917D01*
X-148933Y245333D01*
X-150392Y245125D01*
X-151642Y244500D01*
X-152475Y243042D01*
X-152892Y241791D01*
Y240542D01*
X-152475Y239292D01*
X-151433Y238041D01*
X-150183Y237208D01*
X-148725Y237000D01*
X-147267Y237417D01*
X-145808Y238666D01*
G01X-136767Y237000D02*
Y245333D01*
G01Y243667D02*
X-135725Y244500D01*
X-134683Y245125D01*
X-133225Y245333D01*
X-132183Y245125D01*
X-130933Y244500D01*
G01X-122100Y237000D02*
Y249500D01*
G01Y243250D02*
X-121058Y244500D01*
X-119808Y245125D01*
X-118558Y245333D01*
X-116683Y244917D01*
X-115433Y244083D01*
X-114600Y242625D01*
Y240958D01*
X-115017Y239292D01*
X-115850Y238041D01*
X-117308Y237208D01*
X-118558Y237000D01*
X-119808Y237208D01*
X-121058Y237833D01*
X-122100Y238875D01*
G01X-105975Y242625D02*
X-99308D01*
X-99933Y244083D01*
X-100975Y244917D01*
X-102433Y245333D01*
X-103892Y245125D01*
X-105142Y244500D01*
X-105975Y243042D01*
X-106392Y241791D01*
Y240542D01*
X-105975Y239292D01*
X-104933Y238041D01*
X-103683Y237208D01*
X-102225Y237000D01*
X-100767Y237417D01*
X-99308Y238666D01*
G01X-90267Y237000D02*
Y245333D01*
G01Y243667D02*
X-89225Y244500D01*
X-88183Y245125D01*
X-86725Y245333D01*
X-85683Y245125D01*
X-84433Y244500D01*
G01X-57600Y237000D02*
Y247625D01*
X-57183Y248666D01*
X-56350Y249292D01*
X-55100Y249500D01*
X-53850Y249083D01*
X-53225Y248042D01*
G01X-55725Y244500D02*
X-59892D01*
G01X-40850Y237000D02*
X-42100Y237208D01*
X-43350Y238041D01*
X-44184Y239500D01*
X-44600Y241167D01*
X-44184Y242833D01*
X-43350Y244292D01*
X-42100Y245125D01*
X-40850Y245333D01*
X-39600Y245125D01*
X-38350Y244292D01*
X-37517Y242833D01*
X-37308Y241167D01*
X-37517Y239500D01*
X-38350Y238041D01*
X-39600Y237208D01*
X-40850Y237000D01*
G01X-28267D02*
Y245333D01*
G01Y243667D02*
X-27225Y244500D01*
X-26183Y245125D01*
X-24725Y245333D01*
X-23683Y245125D01*
X-22433Y244500D01*
G01X-16100Y237000D02*
Y245333D01*
G01Y243042D02*
X-15475Y244083D01*
X-14433Y244917D01*
X-12975Y245333D01*
X-11517Y244917D01*
X-10475Y244083D01*
X-9850Y243042D01*
Y237000D01*
G01Y243042D02*
X-9225Y244083D01*
X-8183Y244917D01*
X-6725Y245333D01*
X-5267Y244917D01*
X-4225Y244083D01*
X-3600Y242833D01*
Y237000D01*
G01X9400D02*
Y245333D01*
G01Y243875D02*
X8567Y244708D01*
X7317Y245125D01*
X5858Y245333D01*
X4400Y244917D01*
X3150Y244083D01*
X2316Y242833D01*
X1900Y241167D01*
X2316Y239500D01*
X3150Y238250D01*
X4400Y237417D01*
X5858Y237000D01*
X7317Y237208D01*
X8567Y237833D01*
X9400Y238666D01*
G01X21150Y249500D02*
Y237000D01*
G01X18233Y245333D02*
X24067D01*
G01X52150Y249500D02*
Y237000D01*
G01X49233Y245333D02*
X55067D01*
G01X64108Y237000D02*
Y249500D01*
G01Y243458D02*
X65150Y244500D01*
X66192Y245125D01*
X67858Y245333D01*
X69108Y245125D01*
X70567Y244292D01*
X71192Y243042D01*
Y237000D01*
G01X80025Y242625D02*
X86692D01*
X86067Y244083D01*
X85025Y244917D01*
X83567Y245333D01*
X82108Y245125D01*
X80858Y244500D01*
X80025Y243042D01*
X79608Y241791D01*
Y240542D01*
X80025Y239292D01*
X81067Y238041D01*
X82317Y237208D01*
X83775Y237000D01*
X85233Y237417D01*
X86692Y238666D01*
G01X95733Y237000D02*
Y245333D01*
G01Y243667D02*
X96775Y244500D01*
X97817Y245125D01*
X99275Y245333D01*
X100317Y245125D01*
X101567Y244500D01*
G01X107900Y237000D02*
Y245333D01*
G01Y243042D02*
X108525Y244083D01*
X109567Y244917D01*
X111025Y245333D01*
X112483Y244917D01*
X113525Y244083D01*
X114150Y243042D01*
Y237000D01*
G01Y243042D02*
X114775Y244083D01*
X115817Y244917D01*
X117275Y245333D01*
X118733Y244917D01*
X119775Y244083D01*
X120400Y242833D01*
Y237000D01*
G01X133400D02*
Y245333D01*
G01Y243875D02*
X132567Y244708D01*
X131317Y245125D01*
X129858Y245333D01*
X128400Y244917D01*
X127150Y244083D01*
X126316Y242833D01*
X125900Y241167D01*
X126316Y239500D01*
X127150Y238250D01*
X128400Y237417D01*
X129858Y237000D01*
X131317Y237208D01*
X132567Y237833D01*
X133400Y238666D01*
G01X145150Y237000D02*
Y249500D01*
G01X173233Y237000D02*
Y245333D01*
G01Y243667D02*
X174275Y244500D01*
X175317Y245125D01*
X176775Y245333D01*
X177817Y245125D01*
X179067Y244500D01*
G01X188525Y242625D02*
X195192D01*
X194567Y244083D01*
X193525Y244917D01*
X192067Y245333D01*
X190608Y245125D01*
X189358Y244500D01*
X188525Y243042D01*
X188108Y241791D01*
Y240542D01*
X188525Y239292D01*
X189567Y238041D01*
X190817Y237208D01*
X192275Y237000D01*
X193733Y237417D01*
X195192Y238666D01*
G01X207150Y237000D02*
Y249500D01*
G01X222650Y245333D02*
Y237000D01*
G01Y248666D02*
X222233Y248875D01*
Y249292D01*
X222650Y249500D01*
X223067Y249292D01*
Y248875D01*
X222650Y248666D01*
G01X235025Y242625D02*
X241692D01*
X241067Y244083D01*
X240025Y244917D01*
X238567Y245333D01*
X237108Y245125D01*
X235858Y244500D01*
X235025Y243042D01*
X234608Y241791D01*
Y240542D01*
X235025Y239292D01*
X236067Y238041D01*
X237317Y237208D01*
X238775Y237000D01*
X240233Y237417D01*
X241692Y238666D01*
G01X252400Y237000D02*
Y247625D01*
X252817Y248666D01*
X253650Y249292D01*
X254900Y249500D01*
X256150Y249083D01*
X256775Y248042D01*
G01X254275Y244500D02*
X250108D01*
G01X-238433Y536900D02*
Y549400D01*
X-234267D01*
X-232600Y548775D01*
X-231350Y547942D01*
X-230308Y546692D01*
X-229475Y545233D01*
X-229267Y543150D01*
X-229475Y541067D01*
X-230308Y539608D01*
X-231350Y538358D01*
X-232600Y537525D01*
X-234267Y536900D01*
X-238433D01*
G01X-221475Y542525D02*
X-214808D01*
X-215433Y543983D01*
X-216475Y544817D01*
X-217933Y545233D01*
X-219392Y545025D01*
X-220642Y544400D01*
X-221475Y542942D01*
X-221892Y541691D01*
Y540442D01*
X-221475Y539192D01*
X-220433Y537941D01*
X-219183Y537108D01*
X-217725Y536900D01*
X-216267Y537317D01*
X-214808Y538566D01*
G01X-204100Y536900D02*
Y547525D01*
X-203683Y548566D01*
X-202850Y549192D01*
X-201600Y549400D01*
X-200350Y548983D01*
X-199725Y547942D01*
G01X-202225Y544400D02*
X-206392D01*
G01X-187350Y545233D02*
Y536900D01*
G01Y548566D02*
X-187767Y548775D01*
Y549192D01*
X-187350Y549400D01*
X-186933Y549192D01*
Y548775D01*
X-187350Y548566D01*
G01X-175392Y536900D02*
Y545233D01*
G01Y543150D02*
X-174558Y544192D01*
X-173308Y545025D01*
X-171642Y545233D01*
X-170183Y545025D01*
X-168933Y544192D01*
X-168308Y542733D01*
Y536900D01*
G01X-159475Y542525D02*
X-152808D01*
X-153433Y543983D01*
X-154475Y544817D01*
X-155933Y545233D01*
X-157392Y545025D01*
X-158642Y544400D01*
X-159475Y542942D01*
X-159892Y541691D01*
Y540442D01*
X-159475Y539192D01*
X-158433Y537941D01*
X-157183Y537108D01*
X-155725Y536900D01*
X-154267Y537317D01*
X-152808Y538566D01*
G01X-125350Y549400D02*
Y536900D01*
G01X-128267Y545233D02*
X-122433D01*
G01X-113392Y536900D02*
Y549400D01*
G01Y543358D02*
X-112350Y544400D01*
X-111308Y545025D01*
X-109642Y545233D01*
X-108392Y545025D01*
X-106933Y544192D01*
X-106308Y542942D01*
Y536900D01*
G01X-97475Y542525D02*
X-90808D01*
X-91433Y543983D01*
X-92475Y544817D01*
X-93933Y545233D01*
X-95392Y545025D01*
X-96642Y544400D01*
X-97475Y542942D01*
X-97892Y541691D01*
Y540442D01*
X-97475Y539192D01*
X-96433Y537941D01*
X-95183Y537108D01*
X-93725Y536900D01*
X-92267Y537317D01*
X-90808Y538566D01*
G01X-81767Y536900D02*
Y545233D01*
G01Y543567D02*
X-80725Y544400D01*
X-79683Y545025D01*
X-78225Y545233D01*
X-77183Y545025D01*
X-75933Y544400D01*
G01X-69600Y536900D02*
Y545233D01*
G01Y542942D02*
X-68975Y543983D01*
X-67933Y544817D01*
X-66475Y545233D01*
X-65017Y544817D01*
X-63975Y543983D01*
X-63350Y542942D01*
Y536900D01*
G01Y542942D02*
X-62725Y543983D01*
X-61683Y544817D01*
X-60225Y545233D01*
X-58767Y544817D01*
X-57725Y543983D01*
X-57100Y542733D01*
Y536900D01*
G01X-44100D02*
Y545233D01*
G01Y543775D02*
X-44933Y544608D01*
X-46183Y545025D01*
X-47642Y545233D01*
X-49100Y544817D01*
X-50350Y543983D01*
X-51184Y542733D01*
X-51600Y541067D01*
X-51184Y539400D01*
X-50350Y538150D01*
X-49100Y537317D01*
X-47642Y536900D01*
X-46183Y537108D01*
X-44933Y537733D01*
X-44100Y538566D01*
G01X-32350Y536900D02*
Y549400D01*
G01X-4267Y536900D02*
Y545233D01*
G01Y543567D02*
X-3225Y544400D01*
X-2183Y545025D01*
X-725Y545233D01*
X317Y545025D01*
X1567Y544400D01*
G01X11025Y542525D02*
X17692D01*
X17067Y543983D01*
X16025Y544817D01*
X14567Y545233D01*
X13108Y545025D01*
X11858Y544400D01*
X11025Y542942D01*
X10608Y541691D01*
Y540442D01*
X11025Y539192D01*
X12067Y537941D01*
X13317Y537108D01*
X14775Y536900D01*
X16233Y537317D01*
X17692Y538566D01*
G01X29650Y536900D02*
Y549400D01*
G01X45150Y545233D02*
Y536900D01*
G01Y548566D02*
X44733Y548775D01*
Y549192D01*
X45150Y549400D01*
X45567Y549192D01*
Y548775D01*
X45150Y548566D01*
G01X57525Y542525D02*
X64192D01*
X63567Y543983D01*
X62525Y544817D01*
X61067Y545233D01*
X59608Y545025D01*
X58358Y544400D01*
X57525Y542942D01*
X57108Y541691D01*
Y540442D01*
X57525Y539192D01*
X58567Y537941D01*
X59817Y537108D01*
X61275Y536900D01*
X62733Y537317D01*
X64192Y538566D01*
G01X74900Y536900D02*
Y547525D01*
X75317Y548566D01*
X76150Y549192D01*
X77400Y549400D01*
X78650Y548983D01*
X79275Y547942D01*
G01X76775Y544400D02*
X72608D01*
G01X110483Y544192D02*
X109025Y545025D01*
X107775Y545233D01*
X106108Y544817D01*
X104858Y543983D01*
X104025Y542525D01*
X103816Y541067D01*
X104025Y539608D01*
X104858Y538358D01*
X106108Y537317D01*
X107775Y536900D01*
X109233Y537317D01*
X110483Y538150D01*
G01X122650Y536900D02*
X121400Y537108D01*
X120150Y537941D01*
X119316Y539400D01*
X118900Y541067D01*
X119316Y542733D01*
X120150Y544192D01*
X121400Y545025D01*
X122650Y545233D01*
X123900Y545025D01*
X125150Y544192D01*
X125983Y542733D01*
X126192Y541067D01*
X125983Y539400D01*
X125150Y537941D01*
X123900Y537108D01*
X122650Y536900D01*
G01X134608D02*
Y545233D01*
G01Y543150D02*
X135442Y544192D01*
X136692Y545025D01*
X138358Y545233D01*
X139817Y545025D01*
X141067Y544192D01*
X141692Y542733D01*
Y536900D01*
G01X150108D02*
Y545233D01*
G01Y543150D02*
X150942Y544192D01*
X152192Y545025D01*
X153858Y545233D01*
X155317Y545025D01*
X156567Y544192D01*
X157192Y542733D01*
Y536900D01*
G01X166025Y542525D02*
X172692D01*
X172067Y543983D01*
X171025Y544817D01*
X169567Y545233D01*
X168108Y545025D01*
X166858Y544400D01*
X166025Y542942D01*
X165608Y541691D01*
Y540442D01*
X166025Y539192D01*
X167067Y537941D01*
X168317Y537108D01*
X169775Y536900D01*
X171233Y537317D01*
X172692Y538566D01*
G01X187983Y544192D02*
X186525Y545025D01*
X185275Y545233D01*
X183608Y544817D01*
X182358Y543983D01*
X181525Y542525D01*
X181316Y541067D01*
X181525Y539608D01*
X182358Y538358D01*
X183608Y537317D01*
X185275Y536900D01*
X186733Y537317D01*
X187983Y538150D01*
G01X200150Y549400D02*
Y536900D01*
G01X197233Y545233D02*
X203067D01*
G01X433667Y108283D02*
X442833Y117450D01*
G01X438250Y119117D02*
Y106617D01*
G01X442833Y108283D02*
X433667Y117450D01*
G01X432000Y112867D02*
X444500D01*
G01X449167Y108283D02*
X458333Y117450D01*
G01X453750Y119117D02*
Y106617D01*
G01X458333Y108283D02*
X449167Y117450D01*
G01X447500Y112867D02*
X460000D01*
G01X464667Y108283D02*
X473833Y117450D01*
G01X469250Y119117D02*
Y106617D01*
G01X473833Y108283D02*
X464667Y117450D01*
G01X463000Y112867D02*
X475500D01*
G01X480167Y108283D02*
X489333Y117450D01*
G01X484750Y119117D02*
Y106617D01*
G01X489333Y108283D02*
X480167Y117450D01*
G01X478500Y112867D02*
X491000D01*
G01X500250Y108283D02*
X499833Y108492D01*
Y108908D01*
X500250Y109117D01*
X500667Y108908D01*
Y108492D01*
X500250Y108283D01*
G01Y113908D02*
X499833Y114117D01*
Y114533D01*
X500250Y114742D01*
X500667Y114533D01*
Y114117D01*
X500250Y113908D01*
G01X528750Y121200D02*
X533750D01*
G01X531250D02*
Y108700D01*
G01X528750D02*
X533750D01*
G01X543833Y105575D02*
X545292Y104742D01*
X546958Y104533D01*
X548417Y104742D01*
X549667Y105783D01*
X550500Y107242D01*
Y117033D01*
G01Y115367D02*
X549667Y116200D01*
X548417Y116825D01*
X546958Y117033D01*
X545292Y116617D01*
X544250Y115783D01*
X543416Y114325D01*
X543000Y112867D01*
X543208Y111616D01*
X544042Y110158D01*
X545292Y109117D01*
X546958Y108700D01*
X548208Y108908D01*
X549667Y109741D01*
X550500Y110575D01*
G01X558708Y108700D02*
Y117033D01*
G01Y114950D02*
X559542Y115992D01*
X560792Y116825D01*
X562458Y117033D01*
X563917Y116825D01*
X565167Y115992D01*
X565792Y114533D01*
Y108700D01*
G01X577750D02*
X576500Y108908D01*
X575250Y109741D01*
X574416Y111200D01*
X574000Y112867D01*
X574416Y114533D01*
X575250Y115992D01*
X576500Y116825D01*
X577750Y117033D01*
X579000Y116825D01*
X580250Y115992D01*
X581083Y114533D01*
X581292Y112867D01*
X581083Y111200D01*
X580250Y109741D01*
X579000Y108908D01*
X577750Y108700D01*
G01X590333D02*
Y117033D01*
G01Y115367D02*
X591375Y116200D01*
X592417Y116825D01*
X593875Y117033D01*
X594917Y116825D01*
X596167Y116200D01*
G01X605625Y114325D02*
X612292D01*
X611667Y115783D01*
X610625Y116617D01*
X609167Y117033D01*
X607708Y116825D01*
X606458Y116200D01*
X605625Y114742D01*
X605208Y113491D01*
Y112242D01*
X605625Y110992D01*
X606667Y109741D01*
X607917Y108908D01*
X609375Y108700D01*
X610833Y109117D01*
X612292Y110366D01*
G01X639750Y108700D02*
Y121200D01*
X637250Y118700D01*
G01Y108700D02*
X642250D01*
G01X664500D02*
Y117033D01*
G01Y114742D02*
X665125Y115783D01*
X666167Y116617D01*
X667625Y117033D01*
X669083Y116617D01*
X670125Y115783D01*
X670750Y114742D01*
Y108700D01*
G01Y114742D02*
X671375Y115783D01*
X672417Y116617D01*
X673875Y117033D01*
X675333Y116617D01*
X676375Y115783D01*
X677000Y114533D01*
Y108700D01*
G01X686250Y117033D02*
Y108700D01*
G01Y120366D02*
X685833Y120575D01*
Y120992D01*
X686250Y121200D01*
X686667Y120992D01*
Y120575D01*
X686250Y120366D01*
G01X701750Y108700D02*
Y121200D01*
G01X728167Y108700D02*
Y121200D01*
X732333D01*
X734000Y120575D01*
X735250Y119742D01*
X736292Y118492D01*
X737125Y117033D01*
X737333Y114950D01*
X737125Y112867D01*
X736292Y111408D01*
X735250Y110158D01*
X734000Y109325D01*
X732333Y108700D01*
X728167D01*
G01X745542Y112867D02*
X750958D01*
G01X768333Y120158D02*
X767083Y120783D01*
X765625Y121200D01*
X763958D01*
X762083Y120575D01*
X760625Y119533D01*
X759583Y118283D01*
X758750Y116200D01*
X758541Y114325D01*
X758958Y112450D01*
X759583Y111200D01*
X760833Y109950D01*
X762292Y109117D01*
X763750Y108700D01*
X765208D01*
X766667Y109117D01*
X767917Y109741D01*
X768959Y110575D01*
G01X779250Y108700D02*
X777583Y108908D01*
X776125Y109741D01*
X774875Y110992D01*
X774041Y112450D01*
X773625Y114117D01*
Y115783D01*
X774041Y117450D01*
X774875Y118908D01*
X776125Y120158D01*
X777583Y120992D01*
X779250Y121200D01*
X780917Y120992D01*
X782375Y120158D01*
X783625Y118908D01*
X784459Y117450D01*
X784875Y115783D01*
Y114117D01*
X784459Y112450D01*
X783625Y110992D01*
X782375Y109741D01*
X780917Y108908D01*
X779250Y108700D01*
G01X790167D02*
Y121200D01*
X794333D01*
X796000Y120575D01*
X797250Y119742D01*
X798292Y118492D01*
X799125Y117033D01*
X799333Y114950D01*
X799125Y112867D01*
X798292Y111408D01*
X797250Y110158D01*
X796000Y109325D01*
X794333Y108700D01*
X790167D01*
G01X814417D02*
X806083D01*
Y121200D01*
X814417D01*
G01X811083Y115158D02*
X806083D01*
G01X437858Y153600D02*
Y166100D01*
X447442Y153600D01*
Y166100D01*
G01X458150Y153600D02*
X456900Y153808D01*
X455650Y154641D01*
X454816Y156100D01*
X454400Y157767D01*
X454816Y159433D01*
X455650Y160892D01*
X456900Y161725D01*
X458150Y161933D01*
X459400Y161725D01*
X460650Y160892D01*
X461483Y159433D01*
X461692Y157767D01*
X461483Y156100D01*
X460650Y154641D01*
X459400Y153808D01*
X458150Y153600D01*
G01X473650Y166100D02*
Y153600D01*
G01X470733Y161933D02*
X476567D01*
G01X486025Y159225D02*
X492692D01*
X492067Y160683D01*
X491025Y161517D01*
X489567Y161933D01*
X488108Y161725D01*
X486858Y161100D01*
X486025Y159642D01*
X485608Y158391D01*
Y157142D01*
X486025Y155892D01*
X487067Y154641D01*
X488317Y153808D01*
X489775Y153600D01*
X491233Y154017D01*
X492692Y155266D01*
G01X501525Y155058D02*
X502567Y154225D01*
X504025Y153600D01*
X505275D01*
X506525Y154017D01*
X507358Y154641D01*
X507775Y155475D01*
X507567Y156725D01*
X506733Y157350D01*
X502983Y158600D01*
X502150Y160058D01*
X502567Y161100D01*
X503400Y161725D01*
X504650Y161933D01*
X505900Y161725D01*
X507150Y161100D01*
G01X520150Y153183D02*
X519733Y153392D01*
Y153808D01*
X520150Y154017D01*
X520567Y153808D01*
Y153392D01*
X520150Y153183D01*
G01Y158808D02*
X519733Y159017D01*
Y159433D01*
X520150Y159642D01*
X520567Y159433D01*
Y159017D01*
X520150Y158808D01*
G01X1133341Y624300D02*
X1138550Y611800D01*
X1143759Y624300D01*
G01X1154050Y611800D02*
Y624300D01*
X1151550Y621800D01*
G01Y611800D02*
X1156550D01*
G01X1169550Y611383D02*
X1169133Y611592D01*
Y612008D01*
X1169550Y612217D01*
X1169967Y612008D01*
Y611592D01*
X1169550Y611383D01*
G01X1185050Y624300D02*
X1183383Y623883D01*
X1182133Y622842D01*
X1181300Y621592D01*
X1180675Y619925D01*
X1180467Y618050D01*
X1180675Y616175D01*
X1181300Y614508D01*
X1182133Y613258D01*
X1183383Y612217D01*
X1185050Y611800D01*
X1186717Y612217D01*
X1187967Y613258D01*
X1188800Y614508D01*
X1189425Y616175D01*
X1189633Y618050D01*
X1189425Y619925D01*
X1188800Y621592D01*
X1187967Y622842D01*
X1186717Y623883D01*
X1185050Y624300D01*
G54D11*
G01X-233767Y336900D02*
X-240433D01*
Y346900D01*
X-233767D01*
G01X-236433Y342067D02*
X-240433D01*
G01X-229300Y336900D02*
X-222300Y346900D01*
G01X-229300D02*
X-222300Y336900D01*
G01X-214500Y336567D02*
X-214833Y336733D01*
Y337067D01*
X-214500Y337233D01*
X-214167Y337067D01*
Y336733D01*
X-214500Y336567D01*
G01Y341066D02*
X-214833Y341233D01*
Y341567D01*
X-214500Y341733D01*
X-214167Y341567D01*
Y341233D01*
X-214500Y341066D01*
G01X-195067Y336900D02*
Y346900D01*
X-188733D01*
G01X-191067Y342067D02*
X-195067D01*
G01X-183933Y346900D02*
Y336900D01*
X-177267D01*
G01X-173467D02*
X-169300Y346900D01*
X-165133Y336900D01*
G01X-166633Y340400D02*
X-171967D01*
G01X-161500Y338233D02*
X-160167Y337400D01*
X-158667Y336900D01*
X-157333D01*
X-156000Y337400D01*
X-155000Y338233D01*
X-154500Y339400D01*
X-154833Y340566D01*
X-155667Y341567D01*
X-157167Y342233D01*
X-159167Y342567D01*
X-160333Y343233D01*
X-160833Y344400D01*
X-160500Y345567D01*
X-159667Y346400D01*
X-158500Y346900D01*
X-157333D01*
X-156167Y346567D01*
X-155167Y345733D01*
G01X-150200Y336900D02*
Y346900D01*
G01X-143200D02*
Y336900D01*
G01Y341900D02*
X-150200D01*
G01X-124100Y346900D02*
Y336900D01*
G01X-127933Y346900D02*
X-120267D01*
G01X-116133Y336900D02*
Y346900D01*
X-111967D01*
X-110633Y346400D01*
X-109800Y345733D01*
X-109467Y344400D01*
X-109800Y343067D01*
X-110800Y342233D01*
X-111967Y341733D01*
X-116133D01*
G01X-111967D02*
X-109467Y336900D01*
G01X-101500D02*
Y346900D01*
X-103500Y344900D01*
G01Y336900D02*
X-99500D01*
G01X-90200Y346900D02*
X-91534Y346567D01*
X-92533Y345733D01*
X-93200Y344733D01*
X-93700Y343400D01*
X-93867Y341900D01*
X-93700Y340400D01*
X-93200Y339067D01*
X-92533Y338066D01*
X-91534Y337233D01*
X-90200Y336900D01*
X-88867Y337233D01*
X-87867Y338066D01*
X-87200Y339067D01*
X-86700Y340400D01*
X-86533Y341900D01*
X-86700Y343400D01*
X-87200Y344733D01*
X-87867Y345733D01*
X-88867Y346567D01*
X-90200Y346900D01*
G01X-82567Y338900D02*
X-81567Y337733D01*
X-80234Y337067D01*
X-78733Y336900D01*
X-77400Y337067D01*
X-76067Y337900D01*
X-75233Y338900D01*
X-75067Y339900D01*
X-75400Y341066D01*
X-76567Y341900D01*
X-77733Y342233D01*
X-79233D01*
G01X-77733D02*
X-76733Y342733D01*
X-75900Y343566D01*
X-75567Y344567D01*
X-75900Y345567D01*
X-76733Y346400D01*
X-78233Y346900D01*
X-79733Y346733D01*
X-81233Y346067D01*
G01X-72600Y333567D02*
X-62600D01*
G01X-59133Y338066D02*
X-57967Y337233D01*
X-56633Y336900D01*
X-55300Y337233D01*
X-54133Y338233D01*
X-53300Y339733D01*
X-52967Y341233D01*
Y343067D01*
X-53300Y344567D01*
X-54133Y345900D01*
X-55133Y346567D01*
X-56300Y346900D01*
X-57634Y346567D01*
X-58633Y345900D01*
X-59300Y344900D01*
X-59633Y343566D01*
X-59300Y342400D01*
X-58467Y341233D01*
X-57467Y340566D01*
X-56300Y340400D01*
X-54967Y340733D01*
X-53967Y341567D01*
X-52967Y343067D01*
G01X-48667Y338900D02*
X-47667Y337733D01*
X-46334Y337067D01*
X-44833Y336900D01*
X-43500Y337067D01*
X-42167Y337900D01*
X-41333Y338900D01*
X-41167Y339900D01*
X-41500Y341066D01*
X-42667Y341900D01*
X-43833Y342233D01*
X-45333D01*
G01X-43833D02*
X-42833Y342733D01*
X-42000Y343566D01*
X-41667Y344567D01*
X-42000Y345567D01*
X-42833Y346400D01*
X-44333Y346900D01*
X-45833Y346733D01*
X-47333Y346067D01*
G01X-38700Y333567D02*
X-28700D01*
G01X-26067Y338900D02*
X-25067Y337733D01*
X-23734Y337067D01*
X-22233Y336900D01*
X-20900Y337067D01*
X-19567Y337900D01*
X-18733Y338900D01*
X-18567Y339900D01*
X-18900Y341066D01*
X-20067Y341900D01*
X-21233Y342233D01*
X-22733D01*
G01X-21233D02*
X-20233Y342733D01*
X-19400Y343566D01*
X-19067Y344567D01*
X-19400Y345567D01*
X-20233Y346400D01*
X-21733Y346900D01*
X-23233Y346733D01*
X-24733Y346067D01*
G01X-11100Y346900D02*
X-12434Y346567D01*
X-13433Y345733D01*
X-14100Y344733D01*
X-14600Y343400D01*
X-14767Y341900D01*
X-14600Y340400D01*
X-14100Y339067D01*
X-13433Y338066D01*
X-12434Y337233D01*
X-11100Y336900D01*
X-9767Y337233D01*
X-8767Y338066D01*
X-8100Y339067D01*
X-7600Y340400D01*
X-7433Y341900D01*
X-7600Y343400D01*
X-8100Y344733D01*
X-8767Y345733D01*
X-9767Y346567D01*
X-11100Y346900D01*
G01X200Y336567D02*
X-133Y336733D01*
Y337067D01*
X200Y337233D01*
X533Y337067D01*
Y336733D01*
X200Y336567D01*
G01Y341066D02*
X-133Y341233D01*
Y341567D01*
X200Y341733D01*
X533Y341567D01*
Y341233D01*
X200Y341066D01*
G01X-226767Y478900D02*
X-225767Y477733D01*
X-224434Y477067D01*
X-222933Y476900D01*
X-221600Y477067D01*
X-220267Y477900D01*
X-219433Y478900D01*
X-219267Y479900D01*
X-219600Y481066D01*
X-220767Y481900D01*
X-221933Y482233D01*
X-223433D01*
G01X-221933D02*
X-220933Y482733D01*
X-220100Y483566D01*
X-219767Y484567D01*
X-220100Y485567D01*
X-220933Y486400D01*
X-222433Y486900D01*
X-223933Y486733D01*
X-225433Y486067D01*
G01X-211800Y476567D02*
X-212133Y476733D01*
Y477067D01*
X-211800Y477233D01*
X-211467Y477067D01*
Y476733D01*
X-211800Y476567D01*
G01X-226267Y501233D02*
X-225267Y502233D01*
X-224100Y502733D01*
X-222767Y502900D01*
X-221100Y502567D01*
X-219933Y501733D01*
X-219600Y500733D01*
X-219767Y499733D01*
X-220433Y498900D01*
X-223767Y497233D01*
X-225267Y496067D01*
X-226267Y494400D01*
X-226600Y492900D01*
X-219600D01*
G01X-211800Y492567D02*
X-212133Y492733D01*
Y493067D01*
X-211800Y493233D01*
X-211467Y493067D01*
Y492733D01*
X-211800Y492567D01*
G01X-223100Y508900D02*
Y518900D01*
X-225100Y516900D01*
G01Y508900D02*
X-221100D01*
G01X-211800Y508567D02*
X-212133Y508733D01*
Y509067D01*
X-211800Y509233D01*
X-211467Y509067D01*
Y508733D01*
X-211800Y508567D01*
G01X-192367Y508900D02*
Y518900D01*
X-186033D01*
G01X-188367Y514067D02*
X-192367D01*
G01X-181233Y518900D02*
Y508900D01*
X-174567D01*
G01X-170767D02*
X-166600Y518900D01*
X-162433Y508900D01*
G01X-163933Y512400D02*
X-169267D01*
G01X-158800Y510233D02*
X-157467Y509400D01*
X-155967Y508900D01*
X-154633D01*
X-153300Y509400D01*
X-152300Y510233D01*
X-151800Y511400D01*
X-152133Y512566D01*
X-152967Y513567D01*
X-154467Y514233D01*
X-156467Y514567D01*
X-157633Y515233D01*
X-158133Y516400D01*
X-157800Y517567D01*
X-156967Y518400D01*
X-155800Y518900D01*
X-154633D01*
X-153467Y518567D01*
X-152467Y517733D01*
G01X-147500Y508900D02*
Y518900D01*
G01X-140500D02*
Y508900D01*
G01Y513900D02*
X-147500D01*
G01X-121400Y518900D02*
Y508900D01*
G01X-125233Y518900D02*
X-117567D01*
G01X-113600Y508900D02*
Y518900D01*
G01X-106600D02*
Y508900D01*
G01Y513900D02*
X-113600D01*
G01X-103133Y508900D02*
Y518900D01*
X-98800Y510567D01*
X-94467Y518900D01*
Y508900D01*
G01X-90833Y518900D02*
Y508900D01*
X-84167D01*
G01X-76200D02*
Y518900D01*
X-78200Y516900D01*
G01Y508900D02*
X-74200D01*
G01X-64900Y518900D02*
X-66234Y518567D01*
X-67233Y517733D01*
X-67900Y516733D01*
X-68400Y515400D01*
X-68567Y513900D01*
X-68400Y512400D01*
X-67900Y511067D01*
X-67233Y510066D01*
X-66234Y509233D01*
X-64900Y508900D01*
X-63567Y509233D01*
X-62567Y510066D01*
X-61900Y511067D01*
X-61400Y512400D01*
X-61233Y513900D01*
X-61400Y515400D01*
X-61900Y516733D01*
X-62567Y517733D01*
X-63567Y518567D01*
X-64900Y518900D01*
G01X-42300Y508567D02*
X-42633Y508733D01*
Y509067D01*
X-42300Y509233D01*
X-41967Y509067D01*
Y508733D01*
X-42300Y508567D01*
G01Y513066D02*
X-42633Y513233D01*
Y513567D01*
X-42300Y513733D01*
X-41967Y513567D01*
Y513233D01*
X-42300Y513066D01*
G01X-22867Y508900D02*
Y518900D01*
X-16533D01*
G01X-18867Y514067D02*
X-22867D01*
G01X-11233Y515566D02*
Y510900D01*
X-10567Y509733D01*
X-9567Y509067D01*
X-8400Y508900D01*
X-7233Y509067D01*
X-6233Y509733D01*
X-5567Y510900D01*
G01Y508900D02*
Y515566D01*
G01X2900Y508900D02*
Y518900D01*
G01X14200Y508900D02*
Y518900D01*
G01X39467Y514733D02*
X38300Y515400D01*
X37300Y515566D01*
X35967Y515233D01*
X34967Y514567D01*
X34300Y513400D01*
X34133Y512233D01*
X34300Y511067D01*
X34967Y510066D01*
X35967Y509233D01*
X37300Y508900D01*
X38467Y509233D01*
X39467Y509900D01*
G01X48100Y508900D02*
X47100Y509067D01*
X46100Y509733D01*
X45433Y510900D01*
X45100Y512233D01*
X45433Y513567D01*
X46100Y514733D01*
X47100Y515400D01*
X48100Y515566D01*
X49100Y515400D01*
X50100Y514733D01*
X50767Y513567D01*
X50933Y512233D01*
X50767Y510900D01*
X50100Y509733D01*
X49100Y509067D01*
X48100Y508900D01*
G01X56567D02*
Y515566D01*
G01Y513900D02*
X57233Y514733D01*
X58233Y515400D01*
X59567Y515566D01*
X60733Y515400D01*
X61733Y514733D01*
X62233Y513567D01*
Y508900D01*
G01X70700Y518900D02*
Y508900D01*
G01X68367Y515566D02*
X73033D01*
G01X85000Y508900D02*
Y515566D01*
G01Y514400D02*
X84333Y515067D01*
X83333Y515400D01*
X82167Y515566D01*
X81000Y515233D01*
X80000Y514567D01*
X79333Y513567D01*
X79000Y512233D01*
X79333Y510900D01*
X80000Y509900D01*
X81000Y509233D01*
X82167Y508900D01*
X83333Y509067D01*
X84333Y509567D01*
X85000Y510233D01*
G01X95967Y514733D02*
X94800Y515400D01*
X93800Y515566D01*
X92467Y515233D01*
X91467Y514567D01*
X90800Y513400D01*
X90633Y512233D01*
X90800Y511067D01*
X91467Y510066D01*
X92467Y509233D01*
X93800Y508900D01*
X94967Y509233D01*
X95967Y509900D01*
G01X104600Y518900D02*
Y508900D01*
G01X102267Y515566D02*
X106933D01*
G01X-177467Y-183800D02*
X-184133D01*
Y-173800D01*
X-177467D01*
G01X-180133Y-178633D02*
X-184133D01*
G01X-173000Y-183800D02*
X-166000Y-173800D01*
G01X-173000D02*
X-166000Y-183800D01*
G01X-158200Y-184133D02*
X-158533Y-183967D01*
Y-183633D01*
X-158200Y-183467D01*
X-157867Y-183633D01*
Y-183967D01*
X-158200Y-184133D01*
G01Y-179634D02*
X-158533Y-179467D01*
Y-179133D01*
X-158200Y-178967D01*
X-157867Y-179133D01*
Y-179467D01*
X-158200Y-179634D01*
G01X-138767Y-183800D02*
Y-173800D01*
X-132433D01*
G01X-134767Y-178633D02*
X-138767D01*
G01X-127633Y-173800D02*
Y-183800D01*
X-120967D01*
G01X-117167D02*
X-113000Y-173800D01*
X-108833Y-183800D01*
G01X-110333Y-180300D02*
X-115667D01*
G01X-105200Y-182467D02*
X-103867Y-183300D01*
X-102367Y-183800D01*
X-101033D01*
X-99700Y-183300D01*
X-98700Y-182467D01*
X-98200Y-181300D01*
X-98533Y-180134D01*
X-99367Y-179133D01*
X-100867Y-178467D01*
X-102867Y-178133D01*
X-104033Y-177467D01*
X-104533Y-176300D01*
X-104200Y-175133D01*
X-103367Y-174300D01*
X-102200Y-173800D01*
X-101033D01*
X-99867Y-174133D01*
X-98867Y-174967D01*
G01X-93900Y-183800D02*
Y-173800D01*
G01X-86900D02*
Y-183800D01*
G01Y-178800D02*
X-93900D01*
G01X-67800Y-173800D02*
Y-183800D01*
G01X-71633Y-173800D02*
X-63967D01*
G01X-59833Y-183800D02*
Y-173800D01*
X-55667D01*
X-54333Y-174300D01*
X-53500Y-174967D01*
X-53167Y-176300D01*
X-53500Y-177633D01*
X-54500Y-178467D01*
X-55667Y-178967D01*
X-59833D01*
G01X-55667D02*
X-53167Y-183800D01*
G01X-48367Y-179634D02*
X-47200Y-178467D01*
X-46200Y-177800D01*
X-44867Y-177467D01*
X-43700Y-177800D01*
X-42867Y-178467D01*
X-42200Y-179467D01*
X-42033Y-180633D01*
X-42200Y-181633D01*
X-42867Y-182634D01*
X-43867Y-183467D01*
X-45033Y-183800D01*
X-46367Y-183467D01*
X-47533Y-182467D01*
X-48200Y-180967D01*
X-48367Y-179300D01*
X-48033Y-177134D01*
X-47533Y-175967D01*
X-46700Y-174800D01*
X-45533Y-173967D01*
X-44367Y-173800D01*
X-43200Y-174133D01*
X-42367Y-174967D01*
G01X-33900Y-173800D02*
X-35234Y-174133D01*
X-36233Y-174967D01*
X-36900Y-175967D01*
X-37400Y-177300D01*
X-37567Y-178800D01*
X-37400Y-180300D01*
X-36900Y-181633D01*
X-36233Y-182634D01*
X-35234Y-183467D01*
X-33900Y-183800D01*
X-32567Y-183467D01*
X-31567Y-182634D01*
X-30900Y-181633D01*
X-30400Y-180300D01*
X-30233Y-178800D01*
X-30400Y-177300D01*
X-30900Y-175967D01*
X-31567Y-174967D01*
X-32567Y-174133D01*
X-33900Y-173800D01*
G01X-26100Y-183800D02*
X-19100Y-173800D01*
G01X-26100D02*
X-19100Y-183800D01*
G01X-11300D02*
Y-173800D01*
X-13300Y-175800D01*
G01Y-183800D02*
X-9300D01*
G01X0D02*
Y-173800D01*
X-2000Y-175800D01*
G01Y-183800D02*
X2000D01*
G01X8467Y-182634D02*
X9633Y-183467D01*
X10967Y-183800D01*
X12300Y-183467D01*
X13467Y-182467D01*
X14300Y-180967D01*
X14633Y-179467D01*
Y-177633D01*
X14300Y-176133D01*
X13467Y-174800D01*
X12467Y-174133D01*
X11300Y-173800D01*
X9966Y-174133D01*
X8967Y-174800D01*
X8300Y-175800D01*
X7967Y-177134D01*
X8300Y-178300D01*
X9133Y-179467D01*
X10133Y-180134D01*
X11300Y-180300D01*
X12633Y-179967D01*
X13633Y-179133D01*
X14633Y-177633D01*
G01X17600Y-187133D02*
X27600D01*
G01X30733Y-175467D02*
X31733Y-174467D01*
X32900Y-173967D01*
X34233Y-173800D01*
X35900Y-174133D01*
X37067Y-174967D01*
X37400Y-175967D01*
X37233Y-176967D01*
X36567Y-177800D01*
X33233Y-179467D01*
X31733Y-180633D01*
X30733Y-182300D01*
X30400Y-183800D01*
X37400D01*
G01X45200Y-173800D02*
X43866Y-174133D01*
X42867Y-174967D01*
X42200Y-175967D01*
X41700Y-177300D01*
X41533Y-178800D01*
X41700Y-180300D01*
X42200Y-181633D01*
X42867Y-182634D01*
X43866Y-183467D01*
X45200Y-183800D01*
X46533Y-183467D01*
X47533Y-182634D01*
X48200Y-181633D01*
X48700Y-180300D01*
X48867Y-178800D01*
X48700Y-177300D01*
X48200Y-175967D01*
X47533Y-174967D01*
X46533Y-174133D01*
X45200Y-173800D01*
G01X53000Y-183800D02*
X60000Y-173800D01*
G01X53000D02*
X60000Y-183800D01*
G01X64133Y-181800D02*
X65133Y-182967D01*
X66466Y-183633D01*
X67967Y-183800D01*
X69300Y-183633D01*
X70633Y-182800D01*
X71467Y-181800D01*
X71633Y-180800D01*
X71300Y-179634D01*
X70133Y-178800D01*
X68967Y-178467D01*
X67467D01*
G01X68967D02*
X69967Y-177967D01*
X70800Y-177134D01*
X71133Y-176133D01*
X70800Y-175133D01*
X69967Y-174300D01*
X68467Y-173800D01*
X66967Y-173967D01*
X65467Y-174633D01*
G01X79100Y-173800D02*
X77766Y-174133D01*
X76767Y-174967D01*
X76100Y-175967D01*
X75600Y-177300D01*
X75433Y-178800D01*
X75600Y-180300D01*
X76100Y-181633D01*
X76767Y-182634D01*
X77766Y-183467D01*
X79100Y-183800D01*
X80433Y-183467D01*
X81433Y-182634D01*
X82100Y-181633D01*
X82600Y-180300D01*
X82767Y-178800D01*
X82600Y-177300D01*
X82100Y-175967D01*
X81433Y-174967D01*
X80433Y-174133D01*
X79100Y-173800D01*
G01X-187833Y-134000D02*
Y-124000D01*
X-180167Y-134000D01*
Y-124000D01*
G01X-176867Y-134000D02*
X-172700Y-124000D01*
X-168533Y-134000D01*
G01X-170033Y-130500D02*
X-175367D01*
G01X-165733Y-134000D02*
Y-124000D01*
X-161400Y-132333D01*
X-157067Y-124000D01*
Y-134000D01*
G01X-146767D02*
X-153433D01*
Y-124000D01*
X-146767D01*
G01X-149433Y-128833D02*
X-153433D01*
G01X-138800Y-134333D02*
X-139133Y-134167D01*
Y-133833D01*
X-138800Y-133667D01*
X-138467Y-133833D01*
Y-134167D01*
X-138800Y-134333D01*
G01Y-129834D02*
X-139133Y-129667D01*
Y-129333D01*
X-138800Y-129167D01*
X-138467Y-129333D01*
Y-129667D01*
X-138800Y-129834D01*
G01X-116200Y-124000D02*
Y-134000D01*
G01X-120033Y-124000D02*
X-112367D01*
G01X-108233Y-134000D02*
Y-124000D01*
X-104067D01*
X-102733Y-124500D01*
X-101900Y-125167D01*
X-101567Y-126500D01*
X-101900Y-127833D01*
X-102900Y-128667D01*
X-104067Y-129167D01*
X-108233D01*
G01X-104067D02*
X-101567Y-134000D01*
G01X-97767D02*
X-93600Y-124000D01*
X-89433Y-134000D01*
G01X-90933Y-130500D02*
X-96267D01*
G01X-85800Y-134000D02*
X-78800Y-124000D01*
G01X-85800D02*
X-78800Y-134000D01*
G01X-69667Y-128667D02*
X-69000Y-128167D01*
X-68500Y-127334D01*
X-68167Y-126167D01*
X-68500Y-125167D01*
X-69167Y-124500D01*
X-70333Y-124000D01*
X-74833D01*
Y-134000D01*
X-69333D01*
X-68167Y-133333D01*
X-67500Y-132333D01*
X-67167Y-131167D01*
X-67500Y-130000D01*
X-68500Y-129000D01*
X-69667Y-128667D01*
X-74833D01*
G01X-64700Y-137333D02*
X-54700D01*
G01X-44733Y-124833D02*
X-45733Y-124333D01*
X-46900Y-124000D01*
X-48233D01*
X-49734Y-124500D01*
X-50900Y-125333D01*
X-51733Y-126333D01*
X-52400Y-128000D01*
X-52567Y-129500D01*
X-52233Y-131000D01*
X-51733Y-132000D01*
X-50733Y-133000D01*
X-49567Y-133667D01*
X-48400Y-134000D01*
X-47233D01*
X-46067Y-133667D01*
X-45067Y-133167D01*
X-44233Y-132500D01*
G01X-40600Y-134000D02*
X-33600Y-124000D01*
G01X-40600D02*
X-33600Y-134000D01*
G01X-29467D02*
Y-124000D01*
X-26133D01*
X-24800Y-124500D01*
X-23800Y-125167D01*
X-22967Y-126167D01*
X-22300Y-127334D01*
X-22133Y-129000D01*
X-22300Y-130667D01*
X-22967Y-131833D01*
X-23800Y-132834D01*
X-24800Y-133500D01*
X-26133Y-134000D01*
X-29467D01*
G01X-194100Y500900D02*
X-191767Y490900D01*
X-189100Y500900D01*
X-186433Y490900D01*
X-184100Y500900D01*
G01X-177800Y497566D02*
Y490900D01*
G01Y500233D02*
X-178133Y500400D01*
Y500733D01*
X-177800Y500900D01*
X-177467Y500733D01*
Y500400D01*
X-177800Y500233D01*
G01X-169000Y492066D02*
X-168167Y491400D01*
X-167000Y490900D01*
X-166000D01*
X-165000Y491233D01*
X-164333Y491733D01*
X-164000Y492400D01*
X-164167Y493400D01*
X-164833Y493900D01*
X-167834Y494900D01*
X-168500Y496067D01*
X-168167Y496900D01*
X-167500Y497400D01*
X-166500Y497566D01*
X-165500Y497400D01*
X-164500Y496900D01*
G01X-155200Y500900D02*
Y490900D01*
G01X-157533Y497566D02*
X-152867D01*
G01X-146233Y490900D02*
Y497566D01*
G01Y496233D02*
X-145400Y496900D01*
X-144567Y497400D01*
X-143400Y497566D01*
X-142567Y497400D01*
X-141567Y496900D01*
G01X-132600Y490900D02*
X-133600Y491067D01*
X-134600Y491733D01*
X-135267Y492900D01*
X-135600Y494233D01*
X-135267Y495567D01*
X-134600Y496733D01*
X-133600Y497400D01*
X-132600Y497566D01*
X-131600Y497400D01*
X-130600Y496733D01*
X-129933Y495567D01*
X-129767Y494233D01*
X-129933Y492900D01*
X-130600Y491733D01*
X-131600Y491067D01*
X-132600Y490900D01*
G01X-124133D02*
Y497566D01*
G01Y495900D02*
X-123467Y496733D01*
X-122467Y497400D01*
X-121133Y497566D01*
X-119967Y497400D01*
X-118967Y496733D01*
X-118467Y495567D01*
Y490900D01*
G01X-98700Y500900D02*
Y490900D01*
G01X-102533Y500900D02*
X-94867D01*
G01X-90900Y490900D02*
Y500900D01*
G01X-83900D02*
Y490900D01*
G01Y495900D02*
X-90900D01*
G01X-80433Y490900D02*
Y500900D01*
X-76100Y492567D01*
X-71767Y500900D01*
Y490900D01*
G01X-68133Y500900D02*
Y490900D01*
X-61467D01*
G01X-39200Y500900D02*
Y490900D01*
G01Y492400D02*
X-39867Y491567D01*
X-40867Y491067D01*
X-42033Y490900D01*
X-43367Y491233D01*
X-44367Y492066D01*
X-45033Y493067D01*
X-45200Y494233D01*
X-45033Y495400D01*
X-44367Y496400D01*
X-43367Y497233D01*
X-42033Y497566D01*
X-40867Y497400D01*
X-40033Y497067D01*
X-39200Y496400D01*
G01X-33400Y495400D02*
X-28067D01*
X-28567Y496567D01*
X-29400Y497233D01*
X-30567Y497566D01*
X-31733Y497400D01*
X-32733Y496900D01*
X-33400Y495733D01*
X-33733Y494733D01*
Y493733D01*
X-33400Y492733D01*
X-32567Y491733D01*
X-31567Y491067D01*
X-30400Y490900D01*
X-29233Y491233D01*
X-28067Y492233D01*
G01X-20600Y490900D02*
Y499400D01*
X-20267Y500233D01*
X-19600Y500733D01*
X-18600Y500900D01*
X-17600Y500567D01*
X-17100Y499733D01*
G01X-19100Y496900D02*
X-22433D01*
G01X-5300Y490900D02*
Y497566D01*
G01Y496400D02*
X-5967Y497067D01*
X-6967Y497400D01*
X-8133Y497566D01*
X-9300Y497233D01*
X-10300Y496567D01*
X-10967Y495567D01*
X-11300Y494233D01*
X-10967Y492900D01*
X-10300Y491900D01*
X-9300Y491233D01*
X-8133Y490900D01*
X-6967Y491067D01*
X-5967Y491567D01*
X-5300Y492233D01*
G01X167Y497566D02*
Y492900D01*
X833Y491733D01*
X1833Y491067D01*
X3000Y490900D01*
X4167Y491067D01*
X5167Y491733D01*
X5833Y492900D01*
G01Y490900D02*
Y497566D01*
G01X14300Y490900D02*
Y500900D01*
G01X25600D02*
Y490900D01*
G01X23267Y497566D02*
X27933D01*
G01X48200Y500900D02*
Y490900D01*
G01X45867Y497566D02*
X50533D01*
G01X56000Y487900D02*
X57000Y487567D01*
X58333Y487900D01*
X59167Y488567D01*
X59833Y489400D01*
X60833Y492066D01*
X63000Y497566D01*
G01X57667D02*
X60833Y492066D01*
G01X67800Y487567D02*
Y497566D01*
G01Y496067D02*
X68633Y496900D01*
X69466Y497400D01*
X70800Y497566D01*
X71967Y497400D01*
X73133Y496567D01*
X73633Y495400D01*
X73800Y494233D01*
X73633Y493067D01*
X73133Y491900D01*
X72133Y491233D01*
X70800Y490900D01*
X69633Y491067D01*
X68467Y491567D01*
X67800Y492233D01*
G01X79600Y495400D02*
X84933D01*
X84433Y496567D01*
X83600Y497233D01*
X82433Y497566D01*
X81267Y497400D01*
X80267Y496900D01*
X79600Y495733D01*
X79267Y494733D01*
Y493733D01*
X79600Y492733D01*
X80433Y491733D01*
X81433Y491067D01*
X82600Y490900D01*
X83767Y491233D01*
X84933Y492233D01*
G01X-160767Y-157800D02*
X-167433D01*
Y-147800D01*
X-160767D01*
G01X-163433Y-152633D02*
X-167433D01*
G01X-152800Y-158133D02*
X-153133Y-157967D01*
Y-157633D01*
X-152800Y-157467D01*
X-152467Y-157633D01*
Y-157967D01*
X-152800Y-158133D01*
G01Y-153634D02*
X-153133Y-153467D01*
Y-153133D01*
X-152800Y-152967D01*
X-152467Y-153133D01*
Y-153467D01*
X-152800Y-153634D01*
G01X-148267Y-68400D02*
X-154933D01*
Y-58400D01*
X-148267D01*
G01X-150933Y-63233D02*
X-154933D01*
G01X-161567Y10600D02*
Y20600D01*
X-158233D01*
X-156900Y20100D01*
X-155900Y19433D01*
X-155067Y18433D01*
X-154400Y17266D01*
X-154233Y15600D01*
X-154400Y13933D01*
X-155067Y12767D01*
X-155900Y11766D01*
X-156900Y11100D01*
X-158233Y10600D01*
X-161567D01*
G01X-149867Y132200D02*
X-156533D01*
Y142200D01*
X-149867D01*
G01X-152533Y137367D02*
X-156533D01*
G01X-145233Y142200D02*
Y132200D01*
X-138567D01*
G01X-133933Y142200D02*
Y132200D01*
X-127267D01*
G01X-121300Y142200D02*
X-117300D01*
G01X-119300D02*
Y132200D01*
G01X-121300D02*
X-117300D01*
G01X-111333D02*
Y142200D01*
X-107333D01*
X-106000Y141700D01*
X-105000Y140533D01*
X-104667Y139200D01*
X-105000Y137867D01*
X-105833Y136867D01*
X-107333Y136366D01*
X-111333D01*
G01X-100200Y133533D02*
X-98867Y132700D01*
X-97367Y132200D01*
X-96033D01*
X-94700Y132700D01*
X-93700Y133533D01*
X-93200Y134700D01*
X-93533Y135866D01*
X-94367Y136867D01*
X-95867Y137533D01*
X-97867Y137867D01*
X-99033Y138533D01*
X-99533Y139700D01*
X-99200Y140867D01*
X-98367Y141700D01*
X-97200Y142200D01*
X-96033D01*
X-94867Y141867D01*
X-93867Y141033D01*
G01X-82067Y132200D02*
X-88733D01*
Y142200D01*
X-82067D01*
G01X-84733Y137367D02*
X-88733D01*
G01X-62800Y142200D02*
Y132200D01*
G01X-66633Y142200D02*
X-58967D01*
G01X-54333Y132200D02*
Y142200D01*
G01Y137367D02*
X-53500Y138200D01*
X-52667Y138700D01*
X-51333Y138866D01*
X-50333Y138700D01*
X-49167Y138033D01*
X-48667Y137033D01*
Y132200D01*
G01X-42700Y136700D02*
X-37367D01*
X-37867Y137867D01*
X-38700Y138533D01*
X-39867Y138866D01*
X-41033Y138700D01*
X-42033Y138200D01*
X-42700Y137033D01*
X-43033Y136033D01*
Y135033D01*
X-42700Y134033D01*
X-41867Y133033D01*
X-40867Y132367D01*
X-39700Y132200D01*
X-38533Y132533D01*
X-37367Y133533D01*
G01X-31233Y132200D02*
Y138866D01*
G01Y137533D02*
X-30400Y138200D01*
X-29567Y138700D01*
X-28400Y138866D01*
X-27567Y138700D01*
X-26567Y138200D01*
G01X-22600Y132200D02*
Y138866D01*
G01Y137033D02*
X-22100Y137867D01*
X-21267Y138533D01*
X-20100Y138866D01*
X-18934Y138533D01*
X-18100Y137867D01*
X-17600Y137033D01*
Y132200D01*
G01Y137033D02*
X-17100Y137867D01*
X-16267Y138533D01*
X-15100Y138866D01*
X-13933Y138533D01*
X-13100Y137867D01*
X-12600Y136867D01*
Y132200D01*
G01X-3300D02*
Y138866D01*
G01Y137700D02*
X-3967Y138367D01*
X-4967Y138700D01*
X-6133Y138866D01*
X-7300Y138533D01*
X-8300Y137867D01*
X-8967Y136867D01*
X-9300Y135533D01*
X-8967Y134200D01*
X-8300Y133200D01*
X-7300Y132533D01*
X-6133Y132200D01*
X-4967Y132367D01*
X-3967Y132867D01*
X-3300Y133533D01*
G01X5000Y132200D02*
Y142200D01*
G01X-151400Y374100D02*
X-147400D01*
G01X-149400D02*
Y364100D01*
G01X-151400D02*
X-147400D01*
G01X-140933D02*
Y370766D01*
G01Y369100D02*
X-140267Y369933D01*
X-139267Y370600D01*
X-137933Y370766D01*
X-136767Y370600D01*
X-135767Y369933D01*
X-135267Y368767D01*
Y364100D01*
G01X-129633D02*
Y370766D01*
G01Y369100D02*
X-128967Y369933D01*
X-127967Y370600D01*
X-126633Y370766D01*
X-125467Y370600D01*
X-124467Y369933D01*
X-123967Y368767D01*
Y364100D01*
G01X-118000Y368600D02*
X-112667D01*
X-113167Y369767D01*
X-114000Y370433D01*
X-115167Y370766D01*
X-116333Y370600D01*
X-117333Y370100D01*
X-118000Y368933D01*
X-118333Y367933D01*
Y366933D01*
X-118000Y365933D01*
X-117167Y364933D01*
X-116167Y364267D01*
X-115000Y364100D01*
X-113833Y364433D01*
X-112667Y365433D01*
G01X-106533Y364100D02*
Y370766D01*
G01Y369433D02*
X-105700Y370100D01*
X-104867Y370600D01*
X-103700Y370766D01*
X-102867Y370600D01*
X-101867Y370100D01*
G01X-85267Y364100D02*
Y374100D01*
X-81933D01*
X-80600Y373600D01*
X-79600Y372933D01*
X-78767Y371933D01*
X-78100Y370766D01*
X-77933Y369100D01*
X-78100Y367433D01*
X-78767Y366267D01*
X-79600Y365266D01*
X-80600Y364600D01*
X-81933Y364100D01*
X-85267D01*
G01X-70300Y370766D02*
Y364100D01*
G01Y373433D02*
X-70633Y373600D01*
Y373933D01*
X-70300Y374100D01*
X-69967Y373933D01*
Y373600D01*
X-70300Y373433D01*
G01X-56000Y364100D02*
Y370766D01*
G01Y369600D02*
X-56667Y370267D01*
X-57667Y370600D01*
X-58833Y370766D01*
X-60000Y370433D01*
X-61000Y369767D01*
X-61667Y368767D01*
X-62000Y367433D01*
X-61667Y366100D01*
X-61000Y365100D01*
X-60000Y364433D01*
X-58833Y364100D01*
X-57667Y364267D01*
X-56667Y364767D01*
X-56000Y365433D01*
G01X-52700Y364100D02*
Y370766D01*
G01Y368933D02*
X-52200Y369767D01*
X-51367Y370433D01*
X-50200Y370766D01*
X-49034Y370433D01*
X-48200Y369767D01*
X-47700Y368933D01*
Y364100D01*
G01Y368933D02*
X-47200Y369767D01*
X-46367Y370433D01*
X-45200Y370766D01*
X-44033Y370433D01*
X-43200Y369767D01*
X-42700Y368767D01*
Y364100D01*
G01X-38900Y368600D02*
X-33567D01*
X-34067Y369767D01*
X-34900Y370433D01*
X-36067Y370766D01*
X-37233Y370600D01*
X-38233Y370100D01*
X-38900Y368933D01*
X-39233Y367933D01*
Y366933D01*
X-38900Y365933D01*
X-38067Y364933D01*
X-37067Y364267D01*
X-35900Y364100D01*
X-34733Y364433D01*
X-33567Y365433D01*
G01X-25100Y374100D02*
Y364100D01*
G01X-27433Y370766D02*
X-22767D01*
G01X-16300Y368600D02*
X-10967D01*
X-11467Y369767D01*
X-12300Y370433D01*
X-13467Y370766D01*
X-14633Y370600D01*
X-15633Y370100D01*
X-16300Y368933D01*
X-16633Y367933D01*
Y366933D01*
X-16300Y365933D01*
X-15467Y364933D01*
X-14467Y364267D01*
X-13300Y364100D01*
X-12133Y364433D01*
X-10967Y365433D01*
G01X-4833Y364100D02*
Y370766D01*
G01Y369433D02*
X-4000Y370100D01*
X-3167Y370600D01*
X-2000Y370766D01*
X-1167Y370600D01*
X-167Y370100D01*
G01X-112767Y-158100D02*
X-119433D01*
Y-148100D01*
X-112767D01*
G01X-115433Y-152933D02*
X-119433D01*
G01X-106967Y-156267D02*
X-102633D01*
G01Y-153267D02*
X-106967D01*
G01X-97167Y-156600D02*
X-96167Y-157433D01*
X-95000Y-157933D01*
X-93500Y-158100D01*
X-92000Y-157767D01*
X-90833Y-157100D01*
X-90000Y-155933D01*
X-89833Y-154600D01*
X-90167Y-153267D01*
X-91000Y-152433D01*
X-92167Y-151767D01*
X-93333Y-151600D01*
X-94500Y-151767D01*
X-96000Y-152433D01*
X-95500Y-148100D01*
X-91000D01*
G01X-75233Y-158100D02*
Y-148100D01*
X-70900Y-156433D01*
X-66567Y-148100D01*
Y-158100D01*
G01X-61600Y-148100D02*
X-57600D01*
G01X-59600D02*
Y-158100D01*
G01X-61600D02*
X-57600D01*
G01X-51633Y-148100D02*
Y-158100D01*
X-44967D01*
G01X-40500Y-156767D02*
X-39167Y-157600D01*
X-37667Y-158100D01*
X-36333D01*
X-35000Y-157600D01*
X-34000Y-156767D01*
X-33500Y-155600D01*
X-33833Y-154434D01*
X-34667Y-153433D01*
X-36167Y-152767D01*
X-38167Y-152433D01*
X-39333Y-151767D01*
X-39833Y-150600D01*
X-39500Y-149433D01*
X-38667Y-148600D01*
X-37500Y-148100D01*
X-36333D01*
X-35167Y-148433D01*
X-34167Y-149267D01*
G01X-15233Y-161433D02*
X-16900Y-159767D01*
X-17733Y-158100D01*
Y-151434D01*
X-16900Y-149767D01*
X-15233Y-148100D01*
G01X-100Y-158100D02*
Y-151434D01*
G01Y-152600D02*
X-767Y-151933D01*
X-1767Y-151600D01*
X-2933Y-151434D01*
X-4100Y-151767D01*
X-5100Y-152433D01*
X-5767Y-153433D01*
X-6100Y-154767D01*
X-5767Y-156100D01*
X-5100Y-157100D01*
X-4100Y-157767D01*
X-2933Y-158100D01*
X-1767Y-157933D01*
X-767Y-157433D01*
X-100Y-156767D01*
G01X8200Y-158100D02*
Y-148100D01*
G01X15333Y-151434D02*
X17333Y-158100D01*
X19500Y-151434D01*
X21667Y-158100D01*
X23667Y-151434D01*
G01X33800Y-158100D02*
Y-151434D01*
G01Y-152600D02*
X33133Y-151933D01*
X32133Y-151600D01*
X30967Y-151434D01*
X29800Y-151767D01*
X28800Y-152433D01*
X28133Y-153433D01*
X27800Y-154767D01*
X28133Y-156100D01*
X28800Y-157100D01*
X29800Y-157767D01*
X30967Y-158100D01*
X32133Y-157933D01*
X33133Y-157433D01*
X33800Y-156767D01*
G01X38600Y-161100D02*
X39600Y-161433D01*
X40933Y-161100D01*
X41767Y-160433D01*
X42433Y-159600D01*
X43433Y-156934D01*
X45600Y-151434D01*
G01X40267D02*
X43433Y-156934D01*
G01X50900D02*
X51733Y-157600D01*
X52900Y-158100D01*
X53900D01*
X54900Y-157767D01*
X55567Y-157267D01*
X55900Y-156600D01*
X55733Y-155600D01*
X55067Y-155100D01*
X52066Y-154100D01*
X51400Y-152933D01*
X51733Y-152100D01*
X52400Y-151600D01*
X53400Y-151434D01*
X54400Y-151600D01*
X55400Y-152100D01*
G01X73167Y-158100D02*
Y-148100D01*
G01X78500Y-151434D02*
X73167Y-155267D01*
G01X75333Y-153767D02*
X78833Y-158100D01*
G01X84800Y-153600D02*
X90133D01*
X89633Y-152433D01*
X88800Y-151767D01*
X87633Y-151434D01*
X86467Y-151600D01*
X85467Y-152100D01*
X84800Y-153267D01*
X84467Y-154267D01*
Y-155267D01*
X84800Y-156267D01*
X85633Y-157267D01*
X86633Y-157933D01*
X87800Y-158100D01*
X88967Y-157767D01*
X90133Y-156767D01*
G01X96100Y-153600D02*
X101433D01*
X100933Y-152433D01*
X100100Y-151767D01*
X98933Y-151434D01*
X97767Y-151600D01*
X96767Y-152100D01*
X96100Y-153267D01*
X95767Y-154267D01*
Y-155267D01*
X96100Y-156267D01*
X96933Y-157267D01*
X97933Y-157933D01*
X99100Y-158100D01*
X100267Y-157767D01*
X101433Y-156767D01*
G01X106900Y-161433D02*
Y-151434D01*
G01Y-152933D02*
X107733Y-152100D01*
X108566Y-151600D01*
X109900Y-151434D01*
X111067Y-151600D01*
X112233Y-152433D01*
X112733Y-153600D01*
X112900Y-154767D01*
X112733Y-155933D01*
X112233Y-157100D01*
X111233Y-157767D01*
X109900Y-158100D01*
X108733Y-157933D01*
X107567Y-157433D01*
X106900Y-156767D01*
G01X128833Y-156600D02*
X129833Y-157433D01*
X131000Y-157933D01*
X132500Y-158100D01*
X134000Y-157767D01*
X135167Y-157100D01*
X136000Y-155933D01*
X136167Y-154600D01*
X135833Y-153267D01*
X135000Y-152433D01*
X133833Y-151767D01*
X132667Y-151600D01*
X131500Y-151767D01*
X130000Y-152433D01*
X130500Y-148100D01*
X135000D01*
G01X150100Y-158100D02*
Y-151434D01*
G01Y-153267D02*
X150600Y-152433D01*
X151433Y-151767D01*
X152600Y-151434D01*
X153766Y-151767D01*
X154600Y-152433D01*
X155100Y-153267D01*
Y-158100D01*
G01Y-153267D02*
X155600Y-152433D01*
X156433Y-151767D01*
X157600Y-151434D01*
X158767Y-151767D01*
X159600Y-152433D01*
X160100Y-153433D01*
Y-158100D01*
G01X166400Y-151434D02*
Y-158100D01*
G01Y-148767D02*
X166067Y-148600D01*
Y-148267D01*
X166400Y-148100D01*
X166733Y-148267D01*
Y-148600D01*
X166400Y-148767D01*
G01X177700Y-158100D02*
Y-148100D01*
G01X186500Y-156934D02*
X187333Y-157600D01*
X188500Y-158100D01*
X189500D01*
X190500Y-157767D01*
X191167Y-157267D01*
X191500Y-156600D01*
X191333Y-155600D01*
X190667Y-155100D01*
X187666Y-154100D01*
X187000Y-152933D01*
X187333Y-152100D01*
X188000Y-151600D01*
X189000Y-151434D01*
X190000Y-151600D01*
X191000Y-152100D01*
G01X201133Y-161433D02*
X202800Y-159767D01*
X203633Y-158100D01*
Y-151434D01*
X202800Y-149767D01*
X201133Y-148100D01*
G01X-80033Y-85733D02*
X-81033Y-85233D01*
X-82200Y-84900D01*
X-83533D01*
X-85034Y-85400D01*
X-86200Y-86233D01*
X-87033Y-87233D01*
X-87700Y-88900D01*
X-87867Y-90400D01*
X-87533Y-91900D01*
X-87033Y-92900D01*
X-86033Y-93900D01*
X-84867Y-94567D01*
X-83700Y-94900D01*
X-82533D01*
X-81367Y-94567D01*
X-80367Y-94067D01*
X-79533Y-93400D01*
G01X-88167Y102700D02*
X-84000Y112700D01*
X-79833Y102700D01*
G01X-81333Y106200D02*
X-86667D01*
G01X-56610Y421580D02*
X-53277D01*
Y418580D01*
X-54277Y417580D01*
X-55443Y416913D01*
X-57110Y416580D01*
X-58777Y416913D01*
X-59943Y417580D01*
X-60943Y418580D01*
X-61610Y419747D01*
X-61943Y421080D01*
Y422247D01*
X-61610Y423246D01*
X-60943Y424413D01*
X-59943Y425413D01*
X-58944Y426080D01*
X-57610Y426580D01*
X-56443D01*
X-55110Y426247D01*
X-54110Y425580D01*
G01X-43310Y416580D02*
Y423246D01*
G01Y422080D02*
X-43977Y422747D01*
X-44977Y423080D01*
X-46143Y423246D01*
X-47310Y422913D01*
X-48310Y422247D01*
X-48977Y421247D01*
X-49310Y419913D01*
X-48977Y418580D01*
X-48310Y417580D01*
X-47310Y416913D01*
X-46143Y416580D01*
X-44977Y416747D01*
X-43977Y417247D01*
X-43310Y417913D01*
G01X-38010Y413247D02*
Y423246D01*
G01Y421747D02*
X-37177Y422580D01*
X-36344Y423080D01*
X-35010Y423246D01*
X-33843Y423080D01*
X-32677Y422247D01*
X-32177Y421080D01*
X-32010Y419913D01*
X-32177Y418747D01*
X-32677Y417580D01*
X-33677Y416913D01*
X-35010Y416580D01*
X-36177Y416747D01*
X-37343Y417247D01*
X-38010Y417913D01*
G01X-17410Y426580D02*
X-15077Y416580D01*
X-12410Y426580D01*
X-9743Y416580D01*
X-7410Y426580D01*
G01X-1110Y423246D02*
Y416580D01*
G01Y425913D02*
X-1443Y426080D01*
Y426413D01*
X-1110Y426580D01*
X-777Y426413D01*
Y426080D01*
X-1110Y425913D01*
G01X13190Y426580D02*
Y416580D01*
G01Y418080D02*
X12523Y417247D01*
X11523Y416747D01*
X10357Y416580D01*
X9023Y416913D01*
X8023Y417746D01*
X7357Y418747D01*
X7190Y419913D01*
X7357Y421080D01*
X8023Y422080D01*
X9023Y422913D01*
X10357Y423246D01*
X11523Y423080D01*
X12357Y422747D01*
X13190Y422080D01*
G01X21490Y426580D02*
Y416580D01*
G01X19157Y423246D02*
X23823D01*
G01X29957Y416580D02*
Y426580D01*
G01Y421747D02*
X30790Y422580D01*
X31623Y423080D01*
X32957Y423246D01*
X33957Y423080D01*
X35123Y422413D01*
X35623Y421413D01*
Y416580D01*
G01X-54170Y465180D02*
X-55504Y465347D01*
X-56670Y466013D01*
X-57670Y467013D01*
X-58337Y468180D01*
X-58670Y469513D01*
Y470847D01*
X-58337Y472180D01*
X-57670Y473347D01*
X-56670Y474347D01*
X-55504Y475013D01*
X-54170Y475180D01*
X-52837Y475013D01*
X-51670Y474347D01*
X-50670Y473347D01*
X-50003Y472180D01*
X-49670Y470847D01*
Y469513D01*
X-50003Y468180D01*
X-50670Y467013D01*
X-51670Y466013D01*
X-52837Y465347D01*
X-54170Y465180D01*
G01X-45703Y471846D02*
Y467180D01*
X-45037Y466013D01*
X-44037Y465347D01*
X-42870Y465180D01*
X-41703Y465347D01*
X-40703Y466013D01*
X-40037Y467180D01*
G01Y465180D02*
Y471846D01*
G01X-31570Y475180D02*
Y465180D01*
G01X-33903Y471846D02*
X-29237D01*
G01X-22770Y469680D02*
X-17437D01*
X-17937Y470847D01*
X-18770Y471513D01*
X-19937Y471846D01*
X-21103Y471680D01*
X-22103Y471180D01*
X-22770Y470013D01*
X-23103Y469013D01*
Y468013D01*
X-22770Y467013D01*
X-21937Y466013D01*
X-20937Y465347D01*
X-19770Y465180D01*
X-18603Y465513D01*
X-17437Y466513D01*
G01X-11303Y465180D02*
Y471846D01*
G01Y470513D02*
X-10470Y471180D01*
X-9637Y471680D01*
X-8470Y471846D01*
X-7637Y471680D01*
X-6637Y471180D01*
G01X9963Y465180D02*
Y475180D01*
X13297D01*
X14630Y474680D01*
X15630Y474013D01*
X16463Y473013D01*
X17130Y471846D01*
X17297Y470180D01*
X17130Y468513D01*
X16463Y467347D01*
X15630Y466346D01*
X14630Y465680D01*
X13297Y465180D01*
X9963D01*
G01X24930Y471846D02*
Y465180D01*
G01Y474513D02*
X24597Y474680D01*
Y475013D01*
X24930Y475180D01*
X25263Y475013D01*
Y474680D01*
X24930Y474513D01*
G01X39230Y465180D02*
Y471846D01*
G01Y470680D02*
X38563Y471347D01*
X37563Y471680D01*
X36397Y471846D01*
X35230Y471513D01*
X34230Y470847D01*
X33563Y469847D01*
X33230Y468513D01*
X33563Y467180D01*
X34230Y466180D01*
X35230Y465513D01*
X36397Y465180D01*
X37563Y465347D01*
X38563Y465847D01*
X39230Y466513D01*
G01X42530Y465180D02*
Y471846D01*
G01Y470013D02*
X43030Y470847D01*
X43863Y471513D01*
X45030Y471846D01*
X46196Y471513D01*
X47030Y470847D01*
X47530Y470013D01*
Y465180D01*
G01Y470013D02*
X48030Y470847D01*
X48863Y471513D01*
X50030Y471846D01*
X51197Y471513D01*
X52030Y470847D01*
X52530Y469847D01*
Y465180D01*
G01X56330Y469680D02*
X61663D01*
X61163Y470847D01*
X60330Y471513D01*
X59163Y471846D01*
X57997Y471680D01*
X56997Y471180D01*
X56330Y470013D01*
X55997Y469013D01*
Y468013D01*
X56330Y467013D01*
X57163Y466013D01*
X58163Y465347D01*
X59330Y465180D01*
X60497Y465513D01*
X61663Y466513D01*
G01X70130Y475180D02*
Y465180D01*
G01X67797Y471846D02*
X72463D01*
G01X78930Y469680D02*
X84263D01*
X83763Y470847D01*
X82930Y471513D01*
X81763Y471846D01*
X80597Y471680D01*
X79597Y471180D01*
X78930Y470013D01*
X78597Y469013D01*
Y468013D01*
X78930Y467013D01*
X79763Y466013D01*
X80763Y465347D01*
X81930Y465180D01*
X83097Y465513D01*
X84263Y466513D01*
G01X90397Y465180D02*
Y471846D01*
G01Y470513D02*
X91230Y471180D01*
X92063Y471680D01*
X93230Y471846D01*
X94063Y471680D01*
X95063Y471180D01*
G01X-15067Y16433D02*
X-14400Y16933D01*
X-13900Y17766D01*
X-13567Y18933D01*
X-13900Y19933D01*
X-14567Y20600D01*
X-15733Y21100D01*
X-20233D01*
Y11100D01*
X-14733D01*
X-13567Y11767D01*
X-12900Y12767D01*
X-12567Y13933D01*
X-12900Y15100D01*
X-13900Y16100D01*
X-15067Y16433D01*
X-20233D01*
G01X13900Y281900D02*
X17233D01*
Y278900D01*
X16233Y277900D01*
X15067Y277233D01*
X13400Y276900D01*
X11733Y277233D01*
X10567Y277900D01*
X9567Y278900D01*
X8900Y280067D01*
X8567Y281400D01*
Y282567D01*
X8900Y283566D01*
X9567Y284733D01*
X10567Y285733D01*
X11566Y286400D01*
X12900Y286900D01*
X14067D01*
X15400Y286567D01*
X16400Y285900D01*
G01X27200Y276900D02*
Y283566D01*
G01Y282400D02*
X26533Y283067D01*
X25533Y283400D01*
X24367Y283566D01*
X23200Y283233D01*
X22200Y282567D01*
X21533Y281567D01*
X21200Y280233D01*
X21533Y278900D01*
X22200Y277900D01*
X23200Y277233D01*
X24367Y276900D01*
X25533Y277067D01*
X26533Y277567D01*
X27200Y278233D01*
G01X32500Y273567D02*
Y283566D01*
G01Y282067D02*
X33333Y282900D01*
X34166Y283400D01*
X35500Y283566D01*
X36667Y283400D01*
X37833Y282567D01*
X38333Y281400D01*
X38500Y280233D01*
X38333Y279067D01*
X37833Y277900D01*
X36833Y277233D01*
X35500Y276900D01*
X34333Y277067D01*
X33167Y277567D01*
X32500Y278233D01*
G01X53100Y286900D02*
X55433Y276900D01*
X58100Y286900D01*
X60767Y276900D01*
X63100Y286900D01*
G01X69400Y283566D02*
Y276900D01*
G01Y286233D02*
X69067Y286400D01*
Y286733D01*
X69400Y286900D01*
X69733Y286733D01*
Y286400D01*
X69400Y286233D01*
G01X83700Y286900D02*
Y276900D01*
G01Y278400D02*
X83033Y277567D01*
X82033Y277067D01*
X80867Y276900D01*
X79533Y277233D01*
X78533Y278066D01*
X77867Y279067D01*
X77700Y280233D01*
X77867Y281400D01*
X78533Y282400D01*
X79533Y283233D01*
X80867Y283566D01*
X82033Y283400D01*
X82867Y283067D01*
X83700Y282400D01*
G01X92000Y286900D02*
Y276900D01*
G01X89667Y283566D02*
X94333D01*
G01X100467Y276900D02*
Y286900D01*
G01Y282067D02*
X101300Y282900D01*
X102133Y283400D01*
X103467Y283566D01*
X104467Y283400D01*
X105633Y282733D01*
X106133Y281733D01*
Y276900D01*
G01X112433Y278733D02*
X116767D01*
G01Y281733D02*
X112433D01*
G01X122233Y278900D02*
X123233Y277733D01*
X124566Y277067D01*
X126067Y276900D01*
X127400Y277067D01*
X128733Y277900D01*
X129567Y278900D01*
X129733Y279900D01*
X129400Y281066D01*
X128233Y281900D01*
X127067Y282233D01*
X125567D01*
G01X127067D02*
X128067Y282733D01*
X128900Y283566D01*
X129233Y284567D01*
X128900Y285567D01*
X128067Y286400D01*
X126567Y286900D01*
X125067Y286733D01*
X123567Y286067D01*
G01X137200Y286900D02*
X135866Y286567D01*
X134867Y285733D01*
X134200Y284733D01*
X133700Y283400D01*
X133533Y281900D01*
X133700Y280400D01*
X134200Y279067D01*
X134867Y278066D01*
X135866Y277233D01*
X137200Y276900D01*
X138533Y277233D01*
X139533Y278066D01*
X140200Y279067D01*
X140700Y280400D01*
X140867Y281900D01*
X140700Y283400D01*
X140200Y284733D01*
X139533Y285733D01*
X138533Y286567D01*
X137200Y286900D01*
G01X11067Y292900D02*
Y302900D01*
X18733Y292900D01*
Y302900D01*
G01X23367Y299566D02*
Y294900D01*
X24033Y293733D01*
X25033Y293067D01*
X26200Y292900D01*
X27367Y293067D01*
X28367Y293733D01*
X29033Y294900D01*
G01Y292900D02*
Y299566D01*
G01X32500Y292900D02*
Y299566D01*
G01Y297733D02*
X33000Y298567D01*
X33833Y299233D01*
X35000Y299566D01*
X36166Y299233D01*
X37000Y298567D01*
X37500Y297733D01*
Y292900D01*
G01Y297733D02*
X38000Y298567D01*
X38833Y299233D01*
X40000Y299566D01*
X41167Y299233D01*
X42000Y298567D01*
X42500Y297567D01*
Y292900D01*
G01X56600Y294233D02*
X57933Y293400D01*
X59433Y292900D01*
X60767D01*
X62100Y293400D01*
X63100Y294233D01*
X63600Y295400D01*
X63267Y296566D01*
X62433Y297567D01*
X60933Y298233D01*
X58933Y298567D01*
X57767Y299233D01*
X57267Y300400D01*
X57600Y301567D01*
X58433Y302400D01*
X59600Y302900D01*
X60767D01*
X61933Y302567D01*
X62933Y301733D01*
G01X68400Y289567D02*
Y299566D01*
G01Y298067D02*
X69233Y298900D01*
X70066Y299400D01*
X71400Y299566D01*
X72567Y299400D01*
X73733Y298567D01*
X74233Y297400D01*
X74400Y296233D01*
X74233Y295067D01*
X73733Y293900D01*
X72733Y293233D01*
X71400Y292900D01*
X70233Y293067D01*
X69067Y293567D01*
X68400Y294233D01*
G01X82700Y292900D02*
X81700Y293067D01*
X80700Y293733D01*
X80033Y294900D01*
X79700Y296233D01*
X80033Y297567D01*
X80700Y298733D01*
X81700Y299400D01*
X82700Y299566D01*
X83700Y299400D01*
X84700Y298733D01*
X85367Y297567D01*
X85533Y296233D01*
X85367Y294900D01*
X84700Y293733D01*
X83700Y293067D01*
X82700Y292900D01*
G01X91167D02*
Y302900D01*
G01X96500Y299566D02*
X91167Y295733D01*
G01X93333Y297233D02*
X96833Y292900D01*
G01X102800Y297400D02*
X108133D01*
X107633Y298567D01*
X106800Y299233D01*
X105633Y299566D01*
X104467Y299400D01*
X103467Y298900D01*
X102800Y297733D01*
X102467Y296733D01*
Y295733D01*
X102800Y294733D01*
X103633Y293733D01*
X104633Y293067D01*
X105800Y292900D01*
X106967Y293233D01*
X108133Y294233D01*
G01X114100Y294066D02*
X114933Y293400D01*
X116100Y292900D01*
X117100D01*
X118100Y293233D01*
X118767Y293733D01*
X119100Y294400D01*
X118933Y295400D01*
X118267Y295900D01*
X115266Y296900D01*
X114600Y298067D01*
X114933Y298900D01*
X115600Y299400D01*
X116600Y299566D01*
X117600Y299400D01*
X118600Y298900D01*
G01X125733Y294733D02*
X130067D01*
G01Y297733D02*
X125733D01*
G01X141200Y292900D02*
Y302900D01*
X135033Y295733D01*
X143367D01*
G01X12900Y312900D02*
X11566Y313067D01*
X10400Y313733D01*
X9400Y314733D01*
X8733Y315900D01*
X8400Y317233D01*
Y318567D01*
X8733Y319900D01*
X9400Y321067D01*
X10400Y322067D01*
X11566Y322733D01*
X12900Y322900D01*
X14233Y322733D01*
X15400Y322067D01*
X16400Y321067D01*
X17067Y319900D01*
X17400Y318567D01*
Y317233D01*
X17067Y315900D01*
X16400Y314733D01*
X15400Y313733D01*
X14233Y313067D01*
X12900Y312900D01*
G01X21367Y319566D02*
Y314900D01*
X22033Y313733D01*
X23033Y313067D01*
X24200Y312900D01*
X25367Y313067D01*
X26367Y313733D01*
X27033Y314900D01*
G01Y312900D02*
Y319566D01*
G01X35500Y322900D02*
Y312900D01*
G01X33167Y319566D02*
X37833D01*
G01X44300Y317400D02*
X49633D01*
X49133Y318567D01*
X48300Y319233D01*
X47133Y319566D01*
X45967Y319400D01*
X44967Y318900D01*
X44300Y317733D01*
X43967Y316733D01*
Y315733D01*
X44300Y314733D01*
X45133Y313733D01*
X46133Y313067D01*
X47300Y312900D01*
X48467Y313233D01*
X49633Y314233D01*
G01X55767Y312900D02*
Y319566D01*
G01Y318233D02*
X56600Y318900D01*
X57433Y319400D01*
X58600Y319566D01*
X59433Y319400D01*
X60433Y318900D01*
G01X77033Y312900D02*
Y322900D01*
X80367D01*
X81700Y322400D01*
X82700Y321733D01*
X83533Y320733D01*
X84200Y319566D01*
X84367Y317900D01*
X84200Y316233D01*
X83533Y315067D01*
X82700Y314066D01*
X81700Y313400D01*
X80367Y312900D01*
X77033D01*
G01X92000Y319566D02*
Y312900D01*
G01Y322233D02*
X91667Y322400D01*
Y322733D01*
X92000Y322900D01*
X92333Y322733D01*
Y322400D01*
X92000Y322233D01*
G01X106300Y312900D02*
Y319566D01*
G01Y318400D02*
X105633Y319067D01*
X104633Y319400D01*
X103467Y319566D01*
X102300Y319233D01*
X101300Y318567D01*
X100633Y317567D01*
X100300Y316233D01*
X100633Y314900D01*
X101300Y313900D01*
X102300Y313233D01*
X103467Y312900D01*
X104633Y313067D01*
X105633Y313567D01*
X106300Y314233D01*
G01X109600Y312900D02*
Y319566D01*
G01Y317733D02*
X110100Y318567D01*
X110933Y319233D01*
X112100Y319566D01*
X113266Y319233D01*
X114100Y318567D01*
X114600Y317733D01*
Y312900D01*
G01Y317733D02*
X115100Y318567D01*
X115933Y319233D01*
X117100Y319566D01*
X118267Y319233D01*
X119100Y318567D01*
X119600Y317567D01*
Y312900D01*
G01X123400Y317400D02*
X128733D01*
X128233Y318567D01*
X127400Y319233D01*
X126233Y319566D01*
X125067Y319400D01*
X124067Y318900D01*
X123400Y317733D01*
X123067Y316733D01*
Y315733D01*
X123400Y314733D01*
X124233Y313733D01*
X125233Y313067D01*
X126400Y312900D01*
X127567Y313233D01*
X128733Y314233D01*
G01X137200Y322900D02*
Y312900D01*
G01X134867Y319566D02*
X139533D01*
G01X146000Y317400D02*
X151333D01*
X150833Y318567D01*
X150000Y319233D01*
X148833Y319566D01*
X147667Y319400D01*
X146667Y318900D01*
X146000Y317733D01*
X145667Y316733D01*
Y315733D01*
X146000Y314733D01*
X146833Y313733D01*
X147833Y313067D01*
X149000Y312900D01*
X150167Y313233D01*
X151333Y314233D01*
G01X157467Y312900D02*
Y319566D01*
G01Y318233D02*
X158300Y318900D01*
X159133Y319400D01*
X160300Y319566D01*
X161133Y319400D01*
X162133Y318900D01*
G01X168933Y314733D02*
X173267D01*
G01Y317733D02*
X168933D01*
G01X182400Y312900D02*
Y322900D01*
X180400Y320900D01*
G01Y312900D02*
X184400D01*
G01X193700Y322900D02*
X192366Y322567D01*
X191367Y321733D01*
X190700Y320733D01*
X190200Y319400D01*
X190033Y317900D01*
X190200Y316400D01*
X190700Y315067D01*
X191367Y314066D01*
X192366Y313233D01*
X193700Y312900D01*
X195033Y313233D01*
X196033Y314066D01*
X196700Y315067D01*
X197200Y316400D01*
X197367Y317900D01*
X197200Y319400D01*
X196700Y320733D01*
X196033Y321733D01*
X195033Y322567D01*
X193700Y322900D01*
G01X201333Y314900D02*
X202333Y313733D01*
X203666Y313067D01*
X205167Y312900D01*
X206500Y313067D01*
X207833Y313900D01*
X208667Y314900D01*
X208833Y315900D01*
X208500Y317066D01*
X207333Y317900D01*
X206167Y318233D01*
X204667D01*
G01X206167D02*
X207167Y318733D01*
X208000Y319566D01*
X208333Y320567D01*
X208000Y321567D01*
X207167Y322400D01*
X205667Y322900D01*
X204167Y322733D01*
X202667Y322067D01*
G01X8900Y344900D02*
X12900D01*
G01X10900D02*
Y334900D01*
G01X8900D02*
X12900D01*
G01X19367D02*
Y341566D01*
G01Y339900D02*
X20033Y340733D01*
X21033Y341400D01*
X22367Y341566D01*
X23533Y341400D01*
X24533Y340733D01*
X25033Y339567D01*
Y334900D01*
G01X30667D02*
Y341566D01*
G01Y339900D02*
X31333Y340733D01*
X32333Y341400D01*
X33667Y341566D01*
X34833Y341400D01*
X35833Y340733D01*
X36333Y339567D01*
Y334900D01*
G01X42300Y339400D02*
X47633D01*
X47133Y340567D01*
X46300Y341233D01*
X45133Y341566D01*
X43967Y341400D01*
X42967Y340900D01*
X42300Y339733D01*
X41967Y338733D01*
Y337733D01*
X42300Y336733D01*
X43133Y335733D01*
X44133Y335067D01*
X45300Y334900D01*
X46467Y335233D01*
X47633Y336233D01*
G01X53767Y334900D02*
Y341566D01*
G01Y340233D02*
X54600Y340900D01*
X55433Y341400D01*
X56600Y341566D01*
X57433Y341400D01*
X58433Y340900D01*
G01X75033Y334900D02*
Y344900D01*
X78367D01*
X79700Y344400D01*
X80700Y343733D01*
X81533Y342733D01*
X82200Y341566D01*
X82367Y339900D01*
X82200Y338233D01*
X81533Y337067D01*
X80700Y336066D01*
X79700Y335400D01*
X78367Y334900D01*
X75033D01*
G01X90000Y341566D02*
Y334900D01*
G01Y344233D02*
X89667Y344400D01*
Y344733D01*
X90000Y344900D01*
X90333Y344733D01*
Y344400D01*
X90000Y344233D01*
G01X104300Y334900D02*
Y341566D01*
G01Y340400D02*
X103633Y341067D01*
X102633Y341400D01*
X101467Y341566D01*
X100300Y341233D01*
X99300Y340567D01*
X98633Y339567D01*
X98300Y338233D01*
X98633Y336900D01*
X99300Y335900D01*
X100300Y335233D01*
X101467Y334900D01*
X102633Y335067D01*
X103633Y335567D01*
X104300Y336233D01*
G01X107600Y334900D02*
Y341566D01*
G01Y339733D02*
X108100Y340567D01*
X108933Y341233D01*
X110100Y341566D01*
X111266Y341233D01*
X112100Y340567D01*
X112600Y339733D01*
Y334900D01*
G01Y339733D02*
X113100Y340567D01*
X113933Y341233D01*
X115100Y341566D01*
X116267Y341233D01*
X117100Y340567D01*
X117600Y339567D01*
Y334900D01*
G01X121400Y339400D02*
X126733D01*
X126233Y340567D01*
X125400Y341233D01*
X124233Y341566D01*
X123067Y341400D01*
X122067Y340900D01*
X121400Y339733D01*
X121067Y338733D01*
Y337733D01*
X121400Y336733D01*
X122233Y335733D01*
X123233Y335067D01*
X124400Y334900D01*
X125567Y335233D01*
X126733Y336233D01*
G01X135200Y344900D02*
Y334900D01*
G01X132867Y341566D02*
X137533D01*
G01X144000Y339400D02*
X149333D01*
X148833Y340567D01*
X148000Y341233D01*
X146833Y341566D01*
X145667Y341400D01*
X144667Y340900D01*
X144000Y339733D01*
X143667Y338733D01*
Y337733D01*
X144000Y336733D01*
X144833Y335733D01*
X145833Y335067D01*
X147000Y334900D01*
X148167Y335233D01*
X149333Y336233D01*
G01X155467Y334900D02*
Y341566D01*
G01Y340233D02*
X156300Y340900D01*
X157133Y341400D01*
X158300Y341566D01*
X159133Y341400D01*
X160133Y340900D01*
G01X166933Y336733D02*
X171267D01*
G01Y339733D02*
X166933D01*
G01X177567Y336066D02*
X178733Y335233D01*
X180067Y334900D01*
X181400Y335233D01*
X182567Y336233D01*
X183400Y337733D01*
X183733Y339233D01*
Y341067D01*
X183400Y342567D01*
X182567Y343900D01*
X181567Y344567D01*
X180400Y344900D01*
X179066Y344567D01*
X178067Y343900D01*
X177400Y342900D01*
X177067Y341566D01*
X177400Y340400D01*
X178233Y339233D01*
X179233Y338566D01*
X180400Y338400D01*
X181733Y338733D01*
X182733Y339567D01*
X183733Y341067D01*
G01X188033Y336900D02*
X189033Y335733D01*
X190366Y335067D01*
X191867Y334900D01*
X193200Y335067D01*
X194533Y335900D01*
X195367Y336900D01*
X195533Y337900D01*
X195200Y339066D01*
X194033Y339900D01*
X192867Y340233D01*
X191367D01*
G01X192867D02*
X193867Y340733D01*
X194700Y341566D01*
X195033Y342567D01*
X194700Y343567D01*
X193867Y344400D01*
X192367Y344900D01*
X190867Y344733D01*
X189367Y344067D01*
G54D12*
G01X321700Y-209000D02*
Y-201000D01*
X325500D01*
G01X324100Y-204867D02*
X321700D01*
G01X331600Y-209000D02*
X331000Y-208867D01*
X330400Y-208333D01*
X330000Y-207400D01*
X329800Y-206333D01*
X330000Y-205267D01*
X330400Y-204333D01*
X331000Y-203800D01*
X331600Y-203667D01*
X332200Y-203800D01*
X332800Y-204333D01*
X333200Y-205267D01*
X333300Y-206333D01*
X333200Y-207400D01*
X332800Y-208333D01*
X332200Y-208867D01*
X331600Y-209000D01*
G01X338200D02*
Y-203667D01*
G01Y-204733D02*
X338700Y-204200D01*
X339200Y-203800D01*
X339900Y-203667D01*
X340400Y-203800D01*
X341000Y-204200D01*
G01X354100Y-205400D02*
X357300D01*
X357000Y-204467D01*
X356500Y-203933D01*
X355800Y-203667D01*
X355100Y-203800D01*
X354500Y-204200D01*
X354100Y-205133D01*
X353900Y-205934D01*
Y-206733D01*
X354100Y-207533D01*
X354600Y-208333D01*
X355200Y-208867D01*
X355900Y-209000D01*
X356600Y-208733D01*
X357300Y-207934D01*
G01X362100Y-203667D02*
X365100Y-209000D01*
G01Y-203667D02*
X362100Y-209000D01*
G01X373400D02*
Y-203667D01*
G01Y-204600D02*
X373000Y-204067D01*
X372400Y-203800D01*
X371700Y-203667D01*
X371000Y-203933D01*
X370400Y-204467D01*
X370000Y-205267D01*
X369800Y-206333D01*
X370000Y-207400D01*
X370400Y-208200D01*
X371000Y-208733D01*
X371700Y-209000D01*
X372400Y-208867D01*
X373000Y-208467D01*
X373400Y-207934D01*
G01X376600Y-209000D02*
Y-203667D01*
G01Y-205133D02*
X376900Y-204467D01*
X377400Y-203933D01*
X378100Y-203667D01*
X378800Y-203933D01*
X379300Y-204467D01*
X379600Y-205133D01*
Y-209000D01*
G01Y-205133D02*
X379900Y-204467D01*
X380400Y-203933D01*
X381100Y-203667D01*
X381800Y-203933D01*
X382300Y-204467D01*
X382600Y-205267D01*
Y-209000D01*
G01X385800Y-211667D02*
Y-203667D01*
G01Y-204867D02*
X386300Y-204200D01*
X386800Y-203800D01*
X387600Y-203667D01*
X388300Y-203800D01*
X389000Y-204467D01*
X389300Y-205400D01*
X389400Y-206333D01*
X389300Y-207267D01*
X389000Y-208200D01*
X388400Y-208733D01*
X387600Y-209000D01*
X386900Y-208867D01*
X386200Y-208467D01*
X385800Y-207934D01*
G01X395600Y-209000D02*
Y-201000D01*
G01X402100Y-205400D02*
X405300D01*
X405000Y-204467D01*
X404500Y-203933D01*
X403800Y-203667D01*
X403100Y-203800D01*
X402500Y-204200D01*
X402100Y-205133D01*
X401900Y-205934D01*
Y-206733D01*
X402100Y-207533D01*
X402600Y-208333D01*
X403200Y-208867D01*
X403900Y-209000D01*
X404600Y-208733D01*
X405300Y-207934D01*
G01X411600Y-209267D02*
X411400Y-209133D01*
Y-208867D01*
X411600Y-208733D01*
X411800Y-208867D01*
Y-209133D01*
X411600Y-209267D01*
G01Y-205667D02*
X411400Y-205533D01*
Y-205267D01*
X411600Y-205133D01*
X411800Y-205267D01*
Y-205533D01*
X411600Y-205667D01*
G01X425500Y-209000D02*
Y-201000D01*
G01X429700D02*
Y-209000D01*
G01Y-205000D02*
X425500D01*
G01X435600Y-209000D02*
X435000Y-208867D01*
X434400Y-208333D01*
X434000Y-207400D01*
X433800Y-206333D01*
X434000Y-205267D01*
X434400Y-204333D01*
X435000Y-203800D01*
X435600Y-203667D01*
X436200Y-203800D01*
X436800Y-204333D01*
X437200Y-205267D01*
X437300Y-206333D01*
X437200Y-207400D01*
X436800Y-208333D01*
X436200Y-208867D01*
X435600Y-209000D01*
G01X443600D02*
Y-201000D01*
G01X450100Y-205400D02*
X453300D01*
X453000Y-204467D01*
X452500Y-203933D01*
X451800Y-203667D01*
X451100Y-203800D01*
X450500Y-204200D01*
X450100Y-205133D01*
X449900Y-205934D01*
Y-206733D01*
X450100Y-207533D01*
X450600Y-208333D01*
X451200Y-208867D01*
X451900Y-209000D01*
X452600Y-208733D01*
X453300Y-207934D01*
G01X465400Y-209000D02*
Y-201000D01*
X467400D01*
X468200Y-201400D01*
X468800Y-201933D01*
X469300Y-202733D01*
X469700Y-203667D01*
X469800Y-205000D01*
X469700Y-206333D01*
X469300Y-207267D01*
X468800Y-208067D01*
X468200Y-208600D01*
X467400Y-209000D01*
X465400D01*
G01X475600Y-203667D02*
Y-209000D01*
G01Y-201533D02*
X475400Y-201400D01*
Y-201133D01*
X475600Y-201000D01*
X475800Y-201133D01*
Y-201400D01*
X475600Y-201533D01*
G01X485400Y-209000D02*
Y-203667D01*
G01Y-204600D02*
X485000Y-204067D01*
X484400Y-203800D01*
X483700Y-203667D01*
X483000Y-203933D01*
X482400Y-204467D01*
X482000Y-205267D01*
X481800Y-206333D01*
X482000Y-207400D01*
X482400Y-208200D01*
X483000Y-208733D01*
X483700Y-209000D01*
X484400Y-208867D01*
X485000Y-208467D01*
X485400Y-207934D01*
G01X491600Y-209267D02*
X491400Y-209133D01*
Y-208867D01*
X491600Y-208733D01*
X491800Y-208867D01*
Y-209133D01*
X491600Y-209267D01*
G01X497400Y-207400D02*
X498000Y-208333D01*
X498800Y-208867D01*
X499700Y-209000D01*
X500500Y-208867D01*
X501300Y-208200D01*
X501800Y-207400D01*
X501900Y-206600D01*
X501700Y-205667D01*
X501000Y-205000D01*
X500300Y-204733D01*
X499400D01*
G01X500300D02*
X500900Y-204333D01*
X501400Y-203667D01*
X501600Y-202867D01*
X501400Y-202067D01*
X500900Y-201400D01*
X500000Y-201000D01*
X499100Y-201133D01*
X498200Y-201667D01*
G01X507600Y-209267D02*
X507400Y-209133D01*
Y-208867D01*
X507600Y-208733D01*
X507800Y-208867D01*
Y-209133D01*
X507600Y-209267D01*
G01X515600Y-209000D02*
Y-201000D01*
X514400Y-202600D01*
G01Y-209000D02*
X516800D01*
G01X523600D02*
X524300Y-208867D01*
X525100Y-208467D01*
X525600Y-207800D01*
X525800Y-206867D01*
X525600Y-205934D01*
X525000Y-205133D01*
X524100Y-204733D01*
X523100D01*
X522500Y-204467D01*
X522000Y-203800D01*
X521800Y-202867D01*
X522100Y-201933D01*
X522800Y-201267D01*
X523600Y-201000D01*
X524400Y-201267D01*
X525100Y-201933D01*
X525400Y-202867D01*
X525200Y-203800D01*
X524700Y-204467D01*
X524100Y-204733D01*
X523100D01*
X522200Y-205133D01*
X521600Y-205934D01*
X521400Y-206867D01*
X521600Y-207800D01*
X522100Y-208467D01*
X522900Y-208867D01*
X523600Y-209000D01*
G01X528600D02*
Y-203667D01*
G01Y-205133D02*
X528900Y-204467D01*
X529400Y-203933D01*
X530100Y-203667D01*
X530800Y-203933D01*
X531300Y-204467D01*
X531600Y-205133D01*
Y-209000D01*
G01Y-205133D02*
X531900Y-204467D01*
X532400Y-203933D01*
X533100Y-203667D01*
X533800Y-203933D01*
X534300Y-204467D01*
X534600Y-205267D01*
Y-209000D01*
G01X536600D02*
Y-203667D01*
G01Y-205133D02*
X536900Y-204467D01*
X537400Y-203933D01*
X538100Y-203667D01*
X538800Y-203933D01*
X539300Y-204467D01*
X539600Y-205133D01*
Y-209000D01*
G01Y-205133D02*
X539900Y-204467D01*
X540400Y-203933D01*
X541100Y-203667D01*
X541800Y-203933D01*
X542300Y-204467D01*
X542600Y-205267D01*
Y-209000D01*
G01X555600Y-203667D02*
Y-209000D01*
G01Y-201533D02*
X555400Y-201400D01*
Y-201133D01*
X555600Y-201000D01*
X555800Y-201133D01*
Y-201400D01*
X555600Y-201533D01*
G01X562100Y-208067D02*
X562600Y-208600D01*
X563300Y-209000D01*
X563900D01*
X564500Y-208733D01*
X564900Y-208333D01*
X565100Y-207800D01*
X565000Y-207000D01*
X564600Y-206600D01*
X562800Y-205800D01*
X562400Y-204867D01*
X562600Y-204200D01*
X563000Y-203800D01*
X563600Y-203667D01*
X564200Y-203800D01*
X564800Y-204200D01*
G01X576600Y-209000D02*
Y-203667D01*
G01Y-205133D02*
X576900Y-204467D01*
X577400Y-203933D01*
X578100Y-203667D01*
X578800Y-203933D01*
X579300Y-204467D01*
X579600Y-205133D01*
Y-209000D01*
G01Y-205133D02*
X579900Y-204467D01*
X580400Y-203933D01*
X581100Y-203667D01*
X581800Y-203933D01*
X582300Y-204467D01*
X582600Y-205267D01*
Y-209000D01*
G01X589400D02*
Y-203667D01*
G01Y-204600D02*
X589000Y-204067D01*
X588400Y-203800D01*
X587700Y-203667D01*
X587000Y-203933D01*
X586400Y-204467D01*
X586000Y-205267D01*
X585800Y-206333D01*
X586000Y-207400D01*
X586400Y-208200D01*
X587000Y-208733D01*
X587700Y-209000D01*
X588400Y-208867D01*
X589000Y-208467D01*
X589400Y-207934D01*
G01X594200Y-209000D02*
Y-203667D01*
G01Y-204733D02*
X594700Y-204200D01*
X595200Y-203800D01*
X595900Y-203667D01*
X596400Y-203800D01*
X597000Y-204200D01*
G01X601900Y-209000D02*
Y-201000D01*
G01X605100Y-203667D02*
X601900Y-206733D01*
G01X603200Y-205533D02*
X605300Y-209000D01*
G01X610100Y-205400D02*
X613300D01*
X613000Y-204467D01*
X612500Y-203933D01*
X611800Y-203667D01*
X611100Y-203800D01*
X610500Y-204200D01*
X610100Y-205133D01*
X609900Y-205934D01*
Y-206733D01*
X610100Y-207533D01*
X610600Y-208333D01*
X611200Y-208867D01*
X611900Y-209000D01*
X612600Y-208733D01*
X613300Y-207934D01*
G01X621400Y-201000D02*
Y-209000D01*
G01Y-207800D02*
X621000Y-208467D01*
X620400Y-208867D01*
X619700Y-209000D01*
X618900Y-208733D01*
X618300Y-208067D01*
X617900Y-207267D01*
X617800Y-206333D01*
X617900Y-205400D01*
X618300Y-204600D01*
X618900Y-203933D01*
X619700Y-203667D01*
X620400Y-203800D01*
X620900Y-204067D01*
X621400Y-204600D01*
G01X635600Y-203667D02*
Y-209000D01*
G01Y-201533D02*
X635400Y-201400D01*
Y-201133D01*
X635600Y-201000D01*
X635800Y-201133D01*
Y-201400D01*
X635600Y-201533D01*
G01X641900Y-209000D02*
Y-203667D01*
G01Y-205000D02*
X642300Y-204333D01*
X642900Y-203800D01*
X643700Y-203667D01*
X644400Y-203800D01*
X645000Y-204333D01*
X645300Y-205267D01*
Y-209000D01*
G01X656600D02*
Y-203667D01*
G01Y-205133D02*
X656900Y-204467D01*
X657400Y-203933D01*
X658100Y-203667D01*
X658800Y-203933D01*
X659300Y-204467D01*
X659600Y-205133D01*
Y-209000D01*
G01Y-205133D02*
X659900Y-204467D01*
X660400Y-203933D01*
X661100Y-203667D01*
X661800Y-203933D01*
X662300Y-204467D01*
X662600Y-205267D01*
Y-209000D01*
G01X666100Y-205400D02*
X669300D01*
X669000Y-204467D01*
X668500Y-203933D01*
X667800Y-203667D01*
X667100Y-203800D01*
X666500Y-204200D01*
X666100Y-205133D01*
X665900Y-205934D01*
Y-206733D01*
X666100Y-207533D01*
X666600Y-208333D01*
X667200Y-208867D01*
X667900Y-209000D01*
X668600Y-208733D01*
X669300Y-207934D01*
G01X677200Y-204333D02*
X676500Y-203800D01*
X675900Y-203667D01*
X675100Y-203933D01*
X674500Y-204467D01*
X674100Y-205400D01*
X674000Y-206333D01*
X674100Y-207267D01*
X674500Y-208067D01*
X675100Y-208733D01*
X675900Y-209000D01*
X676600Y-208733D01*
X677200Y-208200D01*
G01X681900Y-209000D02*
Y-201000D01*
G01Y-204867D02*
X682400Y-204200D01*
X682900Y-203800D01*
X683700Y-203667D01*
X684300Y-203800D01*
X685000Y-204333D01*
X685300Y-205133D01*
Y-209000D01*
G01X693400D02*
Y-203667D01*
G01Y-204600D02*
X693000Y-204067D01*
X692400Y-203800D01*
X691700Y-203667D01*
X691000Y-203933D01*
X690400Y-204467D01*
X690000Y-205267D01*
X689800Y-206333D01*
X690000Y-207400D01*
X690400Y-208200D01*
X691000Y-208733D01*
X691700Y-209000D01*
X692400Y-208867D01*
X693000Y-208467D01*
X693400Y-207934D01*
G01X697900Y-209000D02*
Y-203667D01*
G01Y-205000D02*
X698300Y-204333D01*
X698900Y-203800D01*
X699700Y-203667D01*
X700400Y-203800D01*
X701000Y-204333D01*
X701300Y-205267D01*
Y-209000D01*
G01X707600Y-203667D02*
Y-209000D01*
G01Y-201533D02*
X707400Y-201400D01*
Y-201133D01*
X707600Y-201000D01*
X707800Y-201133D01*
Y-201400D01*
X707600Y-201533D01*
G01X717200Y-204333D02*
X716500Y-203800D01*
X715900Y-203667D01*
X715100Y-203933D01*
X714500Y-204467D01*
X714100Y-205400D01*
X714000Y-206333D01*
X714100Y-207267D01*
X714500Y-208067D01*
X715100Y-208733D01*
X715900Y-209000D01*
X716600Y-208733D01*
X717200Y-208200D01*
G01X725400Y-209000D02*
Y-203667D01*
G01Y-204600D02*
X725000Y-204067D01*
X724400Y-203800D01*
X723700Y-203667D01*
X723000Y-203933D01*
X722400Y-204467D01*
X722000Y-205267D01*
X721800Y-206333D01*
X722000Y-207400D01*
X722400Y-208200D01*
X723000Y-208733D01*
X723700Y-209000D01*
X724400Y-208867D01*
X725000Y-208467D01*
X725400Y-207934D01*
G01X731600Y-209000D02*
Y-201000D01*
G01X749400D02*
Y-209000D01*
G01Y-207800D02*
X749000Y-208467D01*
X748400Y-208867D01*
X747700Y-209000D01*
X746900Y-208733D01*
X746300Y-208067D01*
X745900Y-207267D01*
X745800Y-206333D01*
X745900Y-205400D01*
X746300Y-204600D01*
X746900Y-203933D01*
X747700Y-203667D01*
X748400Y-203800D01*
X748900Y-204067D01*
X749400Y-204600D01*
G01X754200Y-209000D02*
Y-203667D01*
G01Y-204733D02*
X754700Y-204200D01*
X755200Y-203800D01*
X755900Y-203667D01*
X756400Y-203800D01*
X757000Y-204200D01*
G01X765400Y-209000D02*
Y-203667D01*
G01Y-204600D02*
X765000Y-204067D01*
X764400Y-203800D01*
X763700Y-203667D01*
X763000Y-203933D01*
X762400Y-204467D01*
X762000Y-205267D01*
X761800Y-206333D01*
X762000Y-207400D01*
X762400Y-208200D01*
X763000Y-208733D01*
X763700Y-209000D01*
X764400Y-208867D01*
X765000Y-208467D01*
X765400Y-207934D01*
G01X769100Y-203667D02*
X770300Y-209000D01*
X771600Y-203667D01*
X772900Y-209000D01*
X774100Y-203667D01*
G01X779600D02*
Y-209000D01*
G01Y-201533D02*
X779400Y-201400D01*
Y-201133D01*
X779600Y-201000D01*
X779800Y-201133D01*
Y-201400D01*
X779600Y-201533D01*
G01X785900Y-209000D02*
Y-203667D01*
G01Y-205000D02*
X786300Y-204333D01*
X786900Y-203800D01*
X787700Y-203667D01*
X788400Y-203800D01*
X789000Y-204333D01*
X789300Y-205267D01*
Y-209000D01*
G01X794200Y-211000D02*
X794900Y-211533D01*
X795700Y-211667D01*
X796400Y-211533D01*
X797000Y-210867D01*
X797400Y-209933D01*
Y-203667D01*
G01Y-204733D02*
X797000Y-204200D01*
X796400Y-203800D01*
X795700Y-203667D01*
X794900Y-203933D01*
X794400Y-204467D01*
X794000Y-205400D01*
X793800Y-206333D01*
X793900Y-207133D01*
X794300Y-208067D01*
X794900Y-208733D01*
X795700Y-209000D01*
X796300Y-208867D01*
X797000Y-208333D01*
X797400Y-207800D01*
G01X813400Y-209000D02*
Y-203667D01*
G01Y-204600D02*
X813000Y-204067D01*
X812400Y-203800D01*
X811700Y-203667D01*
X811000Y-203933D01*
X810400Y-204467D01*
X810000Y-205267D01*
X809800Y-206333D01*
X810000Y-207400D01*
X810400Y-208200D01*
X811000Y-208733D01*
X811700Y-209000D01*
X812400Y-208867D01*
X813000Y-208467D01*
X813400Y-207934D01*
G01X817900Y-209000D02*
Y-203667D01*
G01Y-205000D02*
X818300Y-204333D01*
X818900Y-203800D01*
X819700Y-203667D01*
X820400Y-203800D01*
X821000Y-204333D01*
X821300Y-205267D01*
Y-209000D01*
G01X829400Y-201000D02*
Y-209000D01*
G01Y-207800D02*
X829000Y-208467D01*
X828400Y-208867D01*
X827700Y-209000D01*
X826900Y-208733D01*
X826300Y-208067D01*
X825900Y-207267D01*
X825800Y-206333D01*
X825900Y-205400D01*
X826300Y-204600D01*
X826900Y-203933D01*
X827700Y-203667D01*
X828400Y-203800D01*
X828900Y-204067D01*
X829400Y-204600D01*
G01X841900Y-209000D02*
Y-201000D01*
G01Y-204867D02*
X842400Y-204200D01*
X842900Y-203800D01*
X843700Y-203667D01*
X844300Y-203800D01*
X845000Y-204333D01*
X845300Y-205133D01*
Y-209000D01*
G01X851600D02*
X851000Y-208867D01*
X850400Y-208333D01*
X850000Y-207400D01*
X849800Y-206333D01*
X850000Y-205267D01*
X850400Y-204333D01*
X851000Y-203800D01*
X851600Y-203667D01*
X852200Y-203800D01*
X852800Y-204333D01*
X853200Y-205267D01*
X853300Y-206333D01*
X853200Y-207400D01*
X852800Y-208333D01*
X852200Y-208867D01*
X851600Y-209000D01*
G01X859600D02*
Y-201000D01*
G01X866100Y-205400D02*
X869300D01*
X869000Y-204467D01*
X868500Y-203933D01*
X867800Y-203667D01*
X867100Y-203800D01*
X866500Y-204200D01*
X866100Y-205133D01*
X865900Y-205934D01*
Y-206733D01*
X866100Y-207533D01*
X866600Y-208333D01*
X867200Y-208867D01*
X867900Y-209000D01*
X868600Y-208733D01*
X869300Y-207934D01*
G01X881400Y-209000D02*
Y-201000D01*
X883400D01*
X884200Y-201400D01*
X884800Y-201933D01*
X885300Y-202733D01*
X885700Y-203667D01*
X885800Y-205000D01*
X885700Y-206333D01*
X885300Y-207267D01*
X884800Y-208067D01*
X884200Y-208600D01*
X883400Y-209000D01*
X881400D01*
G01X891600Y-203667D02*
Y-209000D01*
G01Y-201533D02*
X891400Y-201400D01*
Y-201133D01*
X891600Y-201000D01*
X891800Y-201133D01*
Y-201400D01*
X891600Y-201533D01*
G01X901400Y-209000D02*
Y-203667D01*
G01Y-204600D02*
X901000Y-204067D01*
X900400Y-203800D01*
X899700Y-203667D01*
X899000Y-203933D01*
X898400Y-204467D01*
X898000Y-205267D01*
X897800Y-206333D01*
X898000Y-207400D01*
X898400Y-208200D01*
X899000Y-208733D01*
X899700Y-209000D01*
X900400Y-208867D01*
X901000Y-208467D01*
X901400Y-207934D01*
G01X907600Y-209267D02*
X907400Y-209133D01*
Y-208867D01*
X907600Y-208733D01*
X907800Y-208867D01*
Y-209133D01*
X907600Y-209267D01*
G01X923600Y-209000D02*
Y-201000D01*
X922400Y-202600D01*
G01Y-209000D02*
X924800D01*
G01X929700Y-202333D02*
X930300Y-201533D01*
X931000Y-201133D01*
X931800Y-201000D01*
X932800Y-201267D01*
X933500Y-201933D01*
X933700Y-202733D01*
X933600Y-203534D01*
X933200Y-204200D01*
X931200Y-205533D01*
X930300Y-206467D01*
X929700Y-207800D01*
X929500Y-209000D01*
X933700D01*
G01X937700Y-205667D02*
X938400Y-204733D01*
X939000Y-204200D01*
X939800Y-203933D01*
X940500Y-204200D01*
X941000Y-204733D01*
X941400Y-205533D01*
X941500Y-206467D01*
X941400Y-207267D01*
X941000Y-208067D01*
X940400Y-208733D01*
X939700Y-209000D01*
X938900Y-208733D01*
X938200Y-207934D01*
X937800Y-206733D01*
X937700Y-205400D01*
X937900Y-203667D01*
X938200Y-202733D01*
X938700Y-201800D01*
X939400Y-201133D01*
X940100Y-201000D01*
X940800Y-201267D01*
X941300Y-201933D01*
G01X944600Y-209000D02*
Y-203667D01*
G01Y-205133D02*
X944900Y-204467D01*
X945400Y-203933D01*
X946100Y-203667D01*
X946800Y-203933D01*
X947300Y-204467D01*
X947600Y-205133D01*
Y-209000D01*
G01Y-205133D02*
X947900Y-204467D01*
X948400Y-203933D01*
X949100Y-203667D01*
X949800Y-203933D01*
X950300Y-204467D01*
X950600Y-205267D01*
Y-209000D01*
G01X955600Y-203667D02*
Y-209000D01*
G01Y-201533D02*
X955400Y-201400D01*
Y-201133D01*
X955600Y-201000D01*
X955800Y-201133D01*
Y-201400D01*
X955600Y-201533D01*
G01X963600Y-209000D02*
Y-201000D01*
G01X979600Y-203667D02*
Y-209000D01*
G01Y-201533D02*
X979400Y-201400D01*
Y-201133D01*
X979600Y-201000D01*
X979800Y-201133D01*
Y-201400D01*
X979600Y-201533D01*
G01X986100Y-208067D02*
X986600Y-208600D01*
X987300Y-209000D01*
X987900D01*
X988500Y-208733D01*
X988900Y-208333D01*
X989100Y-207800D01*
X989000Y-207000D01*
X988600Y-206600D01*
X986800Y-205800D01*
X986400Y-204867D01*
X986600Y-204200D01*
X987000Y-203800D01*
X987600Y-203667D01*
X988200Y-203800D01*
X988800Y-204200D01*
G01X1000600Y-209000D02*
Y-203667D01*
G01Y-205133D02*
X1000900Y-204467D01*
X1001400Y-203933D01*
X1002100Y-203667D01*
X1002800Y-203933D01*
X1003300Y-204467D01*
X1003600Y-205133D01*
Y-209000D01*
G01Y-205133D02*
X1003900Y-204467D01*
X1004400Y-203933D01*
X1005100Y-203667D01*
X1005800Y-203933D01*
X1006300Y-204467D01*
X1006600Y-205267D01*
Y-209000D01*
G01X1013400D02*
Y-203667D01*
G01Y-204600D02*
X1013000Y-204067D01*
X1012400Y-203800D01*
X1011700Y-203667D01*
X1011000Y-203933D01*
X1010400Y-204467D01*
X1010000Y-205267D01*
X1009800Y-206333D01*
X1010000Y-207400D01*
X1010400Y-208200D01*
X1011000Y-208733D01*
X1011700Y-209000D01*
X1012400Y-208867D01*
X1013000Y-208467D01*
X1013400Y-207934D01*
G01X1018200Y-209000D02*
Y-203667D01*
G01Y-204733D02*
X1018700Y-204200D01*
X1019200Y-203800D01*
X1019900Y-203667D01*
X1020400Y-203800D01*
X1021000Y-204200D01*
G01X1025900Y-209000D02*
Y-201000D01*
G01X1029100Y-203667D02*
X1025900Y-206733D01*
G01X1027200Y-205533D02*
X1029300Y-209000D01*
G01X1034100Y-205400D02*
X1037300D01*
X1037000Y-204467D01*
X1036500Y-203933D01*
X1035800Y-203667D01*
X1035100Y-203800D01*
X1034500Y-204200D01*
X1034100Y-205133D01*
X1033900Y-205934D01*
Y-206733D01*
X1034100Y-207533D01*
X1034600Y-208333D01*
X1035200Y-208867D01*
X1035900Y-209000D01*
X1036600Y-208733D01*
X1037300Y-207934D01*
G01X1045400Y-201000D02*
Y-209000D01*
G01Y-207800D02*
X1045000Y-208467D01*
X1044400Y-208867D01*
X1043700Y-209000D01*
X1042900Y-208733D01*
X1042300Y-208067D01*
X1041900Y-207267D01*
X1041800Y-206333D01*
X1041900Y-205400D01*
X1042300Y-204600D01*
X1042900Y-203933D01*
X1043700Y-203667D01*
X1044400Y-203800D01*
X1044900Y-204067D01*
X1045400Y-204600D01*
G01X1059600Y-203667D02*
Y-209000D01*
G01Y-201533D02*
X1059400Y-201400D01*
Y-201133D01*
X1059600Y-201000D01*
X1059800Y-201133D01*
Y-201400D01*
X1059600Y-201533D01*
G01X1065900Y-209000D02*
Y-203667D01*
G01Y-205000D02*
X1066300Y-204333D01*
X1066900Y-203800D01*
X1067700Y-203667D01*
X1068400Y-203800D01*
X1069000Y-204333D01*
X1069300Y-205267D01*
Y-209000D01*
G01X1084200Y-205000D02*
X1086200D01*
Y-207400D01*
X1085600Y-208200D01*
X1084900Y-208733D01*
X1083900Y-209000D01*
X1082900Y-208733D01*
X1082200Y-208200D01*
X1081600Y-207400D01*
X1081200Y-206467D01*
X1081000Y-205400D01*
Y-204467D01*
X1081200Y-203667D01*
X1081600Y-202733D01*
X1082200Y-201933D01*
X1082800Y-201400D01*
X1083600Y-201000D01*
X1084300D01*
X1085100Y-201267D01*
X1085700Y-201800D01*
G01X1090100Y-205400D02*
X1093300D01*
X1093000Y-204467D01*
X1092500Y-203933D01*
X1091800Y-203667D01*
X1091100Y-203800D01*
X1090500Y-204200D01*
X1090100Y-205133D01*
X1089900Y-205934D01*
Y-206733D01*
X1090100Y-207533D01*
X1090600Y-208333D01*
X1091200Y-208867D01*
X1091900Y-209000D01*
X1092600Y-208733D01*
X1093300Y-207934D01*
G01X1098200Y-209000D02*
Y-203667D01*
G01Y-204733D02*
X1098700Y-204200D01*
X1099200Y-203800D01*
X1099900Y-203667D01*
X1100400Y-203800D01*
X1101000Y-204200D01*
G01X1105800Y-209000D02*
Y-201000D01*
G01Y-205000D02*
X1106300Y-204200D01*
X1106900Y-203800D01*
X1107500Y-203667D01*
X1108400Y-203933D01*
X1109000Y-204467D01*
X1109400Y-205400D01*
Y-206467D01*
X1109200Y-207533D01*
X1108800Y-208333D01*
X1108100Y-208867D01*
X1107500Y-209000D01*
X1106900Y-208867D01*
X1106300Y-208467D01*
X1105800Y-207800D01*
G01X1114100Y-205400D02*
X1117300D01*
X1117000Y-204467D01*
X1116500Y-203933D01*
X1115800Y-203667D01*
X1115100Y-203800D01*
X1114500Y-204200D01*
X1114100Y-205133D01*
X1113900Y-205934D01*
Y-206733D01*
X1114100Y-207533D01*
X1114600Y-208333D01*
X1115200Y-208867D01*
X1115900Y-209000D01*
X1116600Y-208733D01*
X1117300Y-207934D01*
G01X1122200Y-209000D02*
Y-203667D01*
G01Y-204733D02*
X1122700Y-204200D01*
X1123200Y-203800D01*
X1123900Y-203667D01*
X1124400Y-203800D01*
X1125000Y-204200D01*
G01X1139000Y-209000D02*
Y-202200D01*
X1139200Y-201533D01*
X1139600Y-201133D01*
X1140200Y-201000D01*
X1140800Y-201267D01*
X1141100Y-201933D01*
G01X1139900Y-204200D02*
X1137900D01*
G01X1147600Y-203667D02*
Y-209000D01*
G01Y-201533D02*
X1147400Y-201400D01*
Y-201133D01*
X1147600Y-201000D01*
X1147800Y-201133D01*
Y-201400D01*
X1147600Y-201533D01*
G01X1155600Y-209000D02*
Y-201000D01*
G01X1162100Y-205400D02*
X1165300D01*
X1165000Y-204467D01*
X1164500Y-203933D01*
X1163800Y-203667D01*
X1163100Y-203800D01*
X1162500Y-204200D01*
X1162100Y-205133D01*
X1161900Y-205934D01*
Y-206733D01*
X1162100Y-207533D01*
X1162600Y-208333D01*
X1163200Y-208867D01*
X1163900Y-209000D01*
X1164600Y-208733D01*
X1165300Y-207934D01*
G01X1171600Y-209267D02*
X1171400Y-209133D01*
Y-208867D01*
X1171600Y-208733D01*
X1171800Y-208867D01*
Y-209133D01*
X1171600Y-209267D01*
G01X321700Y-176900D02*
Y-182633D01*
X322100Y-183834D01*
X322900Y-184633D01*
X323900Y-184900D01*
X324900Y-184633D01*
X325700Y-183834D01*
X326100Y-182633D01*
Y-176900D01*
G01X330200Y-184900D02*
Y-179567D01*
G01Y-180900D02*
X330600Y-180233D01*
X331200Y-179700D01*
X332000Y-179567D01*
X332700Y-179700D01*
X333300Y-180233D01*
X333600Y-181167D01*
Y-184900D01*
G01X339900Y-179567D02*
Y-184900D01*
G01Y-177433D02*
X339700Y-177300D01*
Y-177033D01*
X339900Y-176900D01*
X340100Y-177033D01*
Y-177300D01*
X339900Y-177433D01*
G01X347900Y-176900D02*
Y-184900D01*
G01X346500Y-179567D02*
X349300D01*
G01X365500Y-180233D02*
X364800Y-179700D01*
X364200Y-179567D01*
X363400Y-179833D01*
X362800Y-180367D01*
X362400Y-181300D01*
X362300Y-182233D01*
X362400Y-183167D01*
X362800Y-183967D01*
X363400Y-184633D01*
X364200Y-184900D01*
X364900Y-184633D01*
X365500Y-184100D01*
G01X371900Y-184900D02*
X371300Y-184767D01*
X370700Y-184233D01*
X370300Y-183300D01*
X370100Y-182233D01*
X370300Y-181167D01*
X370700Y-180233D01*
X371300Y-179700D01*
X371900Y-179567D01*
X372500Y-179700D01*
X373100Y-180233D01*
X373500Y-181167D01*
X373600Y-182233D01*
X373500Y-183300D01*
X373100Y-184233D01*
X372500Y-184767D01*
X371900Y-184900D01*
G01X378200D02*
Y-179567D01*
G01Y-180900D02*
X378600Y-180233D01*
X379200Y-179700D01*
X380000Y-179567D01*
X380700Y-179700D01*
X381300Y-180233D01*
X381600Y-181167D01*
Y-184900D01*
G01X386100Y-179567D02*
X387900Y-184900D01*
X389700Y-179567D01*
G01X394400Y-181300D02*
X397600D01*
X397300Y-180367D01*
X396800Y-179833D01*
X396100Y-179567D01*
X395400Y-179700D01*
X394800Y-180100D01*
X394400Y-181033D01*
X394200Y-181834D01*
Y-182633D01*
X394400Y-183433D01*
X394900Y-184233D01*
X395500Y-184767D01*
X396200Y-184900D01*
X396900Y-184633D01*
X397600Y-183834D01*
G01X402500Y-184900D02*
Y-179567D01*
G01Y-180633D02*
X403000Y-180100D01*
X403500Y-179700D01*
X404200Y-179567D01*
X404700Y-179700D01*
X405300Y-180100D01*
G01X410400Y-183967D02*
X410900Y-184500D01*
X411600Y-184900D01*
X412200D01*
X412800Y-184633D01*
X413200Y-184233D01*
X413400Y-183700D01*
X413300Y-182900D01*
X412900Y-182500D01*
X411100Y-181700D01*
X410700Y-180767D01*
X410900Y-180100D01*
X411300Y-179700D01*
X411900Y-179567D01*
X412500Y-179700D01*
X413100Y-180100D01*
G01X419900Y-179567D02*
Y-184900D01*
G01Y-177433D02*
X419700Y-177300D01*
Y-177033D01*
X419900Y-176900D01*
X420100Y-177033D01*
Y-177300D01*
X419900Y-177433D01*
G01X427900Y-184900D02*
X427300Y-184767D01*
X426700Y-184233D01*
X426300Y-183300D01*
X426100Y-182233D01*
X426300Y-181167D01*
X426700Y-180233D01*
X427300Y-179700D01*
X427900Y-179567D01*
X428500Y-179700D01*
X429100Y-180233D01*
X429500Y-181167D01*
X429600Y-182233D01*
X429500Y-183300D01*
X429100Y-184233D01*
X428500Y-184767D01*
X427900Y-184900D01*
G01X434200D02*
Y-179567D01*
G01Y-180900D02*
X434600Y-180233D01*
X435200Y-179700D01*
X436000Y-179567D01*
X436700Y-179700D01*
X437300Y-180233D01*
X437600Y-181167D01*
Y-184900D01*
G01X450400Y-181300D02*
X453600D01*
X453300Y-180367D01*
X452800Y-179833D01*
X452100Y-179567D01*
X451400Y-179700D01*
X450800Y-180100D01*
X450400Y-181033D01*
X450200Y-181834D01*
Y-182633D01*
X450400Y-183433D01*
X450900Y-184233D01*
X451500Y-184767D01*
X452200Y-184900D01*
X452900Y-184633D01*
X453600Y-183834D01*
G01X458500Y-184900D02*
Y-179567D01*
G01Y-180633D02*
X459000Y-180100D01*
X459500Y-179700D01*
X460200Y-179567D01*
X460700Y-179700D01*
X461300Y-180100D01*
G01X466500Y-184900D02*
Y-179567D01*
G01Y-180633D02*
X467000Y-180100D01*
X467500Y-179700D01*
X468200Y-179567D01*
X468700Y-179700D01*
X469300Y-180100D01*
G01X475900Y-184900D02*
X475300Y-184767D01*
X474700Y-184233D01*
X474300Y-183300D01*
X474100Y-182233D01*
X474300Y-181167D01*
X474700Y-180233D01*
X475300Y-179700D01*
X475900Y-179567D01*
X476500Y-179700D01*
X477100Y-180233D01*
X477500Y-181167D01*
X477600Y-182233D01*
X477500Y-183300D01*
X477100Y-184233D01*
X476500Y-184767D01*
X475900Y-184900D01*
G01X482500D02*
Y-179567D01*
G01Y-180633D02*
X483000Y-180100D01*
X483500Y-179700D01*
X484200Y-179567D01*
X484700Y-179700D01*
X485300Y-180100D01*
G01X498100Y-184900D02*
Y-176900D01*
G01Y-180900D02*
X498600Y-180100D01*
X499200Y-179700D01*
X499800Y-179567D01*
X500700Y-179833D01*
X501300Y-180367D01*
X501700Y-181300D01*
Y-182367D01*
X501500Y-183433D01*
X501100Y-184233D01*
X500400Y-184767D01*
X499800Y-184900D01*
X499200Y-184767D01*
X498600Y-184367D01*
X498100Y-183700D01*
G01X506400Y-181300D02*
X509600D01*
X509300Y-180367D01*
X508800Y-179833D01*
X508100Y-179567D01*
X507400Y-179700D01*
X506800Y-180100D01*
X506400Y-181033D01*
X506200Y-181834D01*
Y-182633D01*
X506400Y-183433D01*
X506900Y-184233D01*
X507500Y-184767D01*
X508200Y-184900D01*
X508900Y-184633D01*
X509600Y-183834D01*
G01X515900Y-176900D02*
Y-184900D01*
G01X514500Y-179567D02*
X517300D01*
G01X521400D02*
X522600Y-184900D01*
X523900Y-179567D01*
X525200Y-184900D01*
X526400Y-179567D01*
G01X530400Y-181300D02*
X533600D01*
X533300Y-180367D01*
X532800Y-179833D01*
X532100Y-179567D01*
X531400Y-179700D01*
X530800Y-180100D01*
X530400Y-181033D01*
X530200Y-181834D01*
Y-182633D01*
X530400Y-183433D01*
X530900Y-184233D01*
X531500Y-184767D01*
X532200Y-184900D01*
X532900Y-184633D01*
X533600Y-183834D01*
G01X538400Y-181300D02*
X541600D01*
X541300Y-180367D01*
X540800Y-179833D01*
X540100Y-179567D01*
X539400Y-179700D01*
X538800Y-180100D01*
X538400Y-181033D01*
X538200Y-181834D01*
Y-182633D01*
X538400Y-183433D01*
X538900Y-184233D01*
X539500Y-184767D01*
X540200Y-184900D01*
X540900Y-184633D01*
X541600Y-183834D01*
G01X546200Y-184900D02*
Y-179567D01*
G01Y-180900D02*
X546600Y-180233D01*
X547200Y-179700D01*
X548000Y-179567D01*
X548700Y-179700D01*
X549300Y-180233D01*
X549600Y-181167D01*
Y-184900D01*
G01X560900D02*
Y-179567D01*
G01Y-181033D02*
X561200Y-180367D01*
X561700Y-179833D01*
X562400Y-179567D01*
X563100Y-179833D01*
X563600Y-180367D01*
X563900Y-181033D01*
Y-184900D01*
G01Y-181033D02*
X564200Y-180367D01*
X564700Y-179833D01*
X565400Y-179567D01*
X566100Y-179833D01*
X566600Y-180367D01*
X566900Y-181167D01*
Y-184900D01*
G01X570400Y-181300D02*
X573600D01*
X573300Y-180367D01*
X572800Y-179833D01*
X572100Y-179567D01*
X571400Y-179700D01*
X570800Y-180100D01*
X570400Y-181033D01*
X570200Y-181834D01*
Y-182633D01*
X570400Y-183433D01*
X570900Y-184233D01*
X571500Y-184767D01*
X572200Y-184900D01*
X572900Y-184633D01*
X573600Y-183834D01*
G01X579900Y-176900D02*
Y-184900D01*
G01X578500Y-179567D02*
X581300D01*
G01X586500Y-184900D02*
Y-179567D01*
G01Y-180633D02*
X587000Y-180100D01*
X587500Y-179700D01*
X588200Y-179567D01*
X588700Y-179700D01*
X589300Y-180100D01*
G01X595900Y-179567D02*
Y-184900D01*
G01Y-177433D02*
X595700Y-177300D01*
Y-177033D01*
X595900Y-176900D01*
X596100Y-177033D01*
Y-177300D01*
X595900Y-177433D01*
G01X605500Y-180233D02*
X604800Y-179700D01*
X604200Y-179567D01*
X603400Y-179833D01*
X602800Y-180367D01*
X602400Y-181300D01*
X602300Y-182233D01*
X602400Y-183167D01*
X602800Y-183967D01*
X603400Y-184633D01*
X604200Y-184900D01*
X604900Y-184633D01*
X605500Y-184100D01*
G01X621700Y-184900D02*
Y-179567D01*
G01Y-180500D02*
X621300Y-179967D01*
X620700Y-179700D01*
X620000Y-179567D01*
X619300Y-179833D01*
X618700Y-180367D01*
X618300Y-181167D01*
X618100Y-182233D01*
X618300Y-183300D01*
X618700Y-184100D01*
X619300Y-184633D01*
X620000Y-184900D01*
X620700Y-184767D01*
X621300Y-184367D01*
X621700Y-183834D01*
G01X626200Y-184900D02*
Y-179567D01*
G01Y-180900D02*
X626600Y-180233D01*
X627200Y-179700D01*
X628000Y-179567D01*
X628700Y-179700D01*
X629300Y-180233D01*
X629600Y-181167D01*
Y-184900D01*
G01X637700Y-176900D02*
Y-184900D01*
G01Y-183700D02*
X637300Y-184367D01*
X636700Y-184767D01*
X636000Y-184900D01*
X635200Y-184633D01*
X634600Y-183967D01*
X634200Y-183167D01*
X634100Y-182233D01*
X634200Y-181300D01*
X634600Y-180500D01*
X635200Y-179833D01*
X636000Y-179567D01*
X636700Y-179700D01*
X637200Y-179967D01*
X637700Y-180500D01*
G01X653900Y-184900D02*
X649900D01*
Y-176900D01*
X653900D01*
G01X652300Y-180767D02*
X649900D01*
G01X658200Y-184900D02*
Y-179567D01*
G01Y-180900D02*
X658600Y-180233D01*
X659200Y-179700D01*
X660000Y-179567D01*
X660700Y-179700D01*
X661300Y-180233D01*
X661600Y-181167D01*
Y-184900D01*
G01X666500Y-186900D02*
X667200Y-187433D01*
X668000Y-187567D01*
X668700Y-187433D01*
X669300Y-186767D01*
X669700Y-185833D01*
Y-179567D01*
G01Y-180633D02*
X669300Y-180100D01*
X668700Y-179700D01*
X668000Y-179567D01*
X667200Y-179833D01*
X666700Y-180367D01*
X666300Y-181300D01*
X666100Y-182233D01*
X666200Y-183033D01*
X666600Y-183967D01*
X667200Y-184633D01*
X668000Y-184900D01*
X668600Y-184767D01*
X669300Y-184233D01*
X669700Y-183700D01*
G01X675900Y-184900D02*
Y-176900D01*
G01X683900Y-179567D02*
Y-184900D01*
G01Y-177433D02*
X683700Y-177300D01*
Y-177033D01*
X683900Y-176900D01*
X684100Y-177033D01*
Y-177300D01*
X683900Y-177433D01*
G01X690400Y-183967D02*
X690900Y-184500D01*
X691600Y-184900D01*
X692200D01*
X692800Y-184633D01*
X693200Y-184233D01*
X693400Y-183700D01*
X693300Y-182900D01*
X692900Y-182500D01*
X691100Y-181700D01*
X690700Y-180767D01*
X690900Y-180100D01*
X691300Y-179700D01*
X691900Y-179567D01*
X692500Y-179700D01*
X693100Y-180100D01*
G01X698200Y-184900D02*
Y-176900D01*
G01Y-180767D02*
X698700Y-180100D01*
X699200Y-179700D01*
X700000Y-179567D01*
X700600Y-179700D01*
X701300Y-180233D01*
X701600Y-181033D01*
Y-184900D01*
G01X714400Y-183967D02*
X714900Y-184500D01*
X715600Y-184900D01*
X716200D01*
X716800Y-184633D01*
X717200Y-184233D01*
X717400Y-183700D01*
X717300Y-182900D01*
X716900Y-182500D01*
X715100Y-181700D01*
X714700Y-180767D01*
X714900Y-180100D01*
X715300Y-179700D01*
X715900Y-179567D01*
X716500Y-179700D01*
X717100Y-180100D01*
G01X721800Y-187300D02*
X722400Y-187567D01*
X723200Y-187300D01*
X723700Y-186767D01*
X724100Y-186100D01*
X724700Y-183967D01*
X726000Y-179567D01*
G01X722800D02*
X724700Y-183967D01*
G01X730400D02*
X730900Y-184500D01*
X731600Y-184900D01*
X732200D01*
X732800Y-184633D01*
X733200Y-184233D01*
X733400Y-183700D01*
X733300Y-182900D01*
X732900Y-182500D01*
X731100Y-181700D01*
X730700Y-180767D01*
X730900Y-180100D01*
X731300Y-179700D01*
X731900Y-179567D01*
X732500Y-179700D01*
X733100Y-180100D01*
G01X739900Y-176900D02*
Y-184900D01*
G01X738500Y-179567D02*
X741300D01*
G01X746400Y-181300D02*
X749600D01*
X749300Y-180367D01*
X748800Y-179833D01*
X748100Y-179567D01*
X747400Y-179700D01*
X746800Y-180100D01*
X746400Y-181033D01*
X746200Y-181834D01*
Y-182633D01*
X746400Y-183433D01*
X746900Y-184233D01*
X747500Y-184767D01*
X748200Y-184900D01*
X748900Y-184633D01*
X749600Y-183834D01*
G01X752900Y-184900D02*
Y-179567D01*
G01Y-181033D02*
X753200Y-180367D01*
X753700Y-179833D01*
X754400Y-179567D01*
X755100Y-179833D01*
X755600Y-180367D01*
X755900Y-181033D01*
Y-184900D01*
G01Y-181033D02*
X756200Y-180367D01*
X756700Y-179833D01*
X757400Y-179567D01*
X758100Y-179833D01*
X758600Y-180367D01*
X758900Y-181167D01*
Y-184900D01*
G01X771900Y-179567D02*
Y-184900D01*
G01Y-177433D02*
X771700Y-177300D01*
Y-177033D01*
X771900Y-176900D01*
X772100Y-177033D01*
Y-177300D01*
X771900Y-177433D01*
G01X778400Y-183967D02*
X778900Y-184500D01*
X779600Y-184900D01*
X780200D01*
X780800Y-184633D01*
X781200Y-184233D01*
X781400Y-183700D01*
X781300Y-182900D01*
X780900Y-182500D01*
X779100Y-181700D01*
X778700Y-180767D01*
X778900Y-180100D01*
X779300Y-179700D01*
X779900Y-179567D01*
X780500Y-179700D01*
X781100Y-180100D01*
G01X795900Y-184900D02*
Y-176900D01*
G01X802400Y-181300D02*
X805600D01*
X805300Y-180367D01*
X804800Y-179833D01*
X804100Y-179567D01*
X803400Y-179700D01*
X802800Y-180100D01*
X802400Y-181033D01*
X802200Y-181834D01*
Y-182633D01*
X802400Y-183433D01*
X802900Y-184233D01*
X803500Y-184767D01*
X804200Y-184900D01*
X804900Y-184633D01*
X805600Y-183834D01*
G01X810400Y-183967D02*
X810900Y-184500D01*
X811600Y-184900D01*
X812200D01*
X812800Y-184633D01*
X813200Y-184233D01*
X813400Y-183700D01*
X813300Y-182900D01*
X812900Y-182500D01*
X811100Y-181700D01*
X810700Y-180767D01*
X810900Y-180100D01*
X811300Y-179700D01*
X811900Y-179567D01*
X812500Y-179700D01*
X813100Y-180100D01*
G01X818400Y-183967D02*
X818900Y-184500D01*
X819600Y-184900D01*
X820200D01*
X820800Y-184633D01*
X821200Y-184233D01*
X821400Y-183700D01*
X821300Y-182900D01*
X820900Y-182500D01*
X819100Y-181700D01*
X818700Y-180767D01*
X818900Y-180100D01*
X819300Y-179700D01*
X819900Y-179567D01*
X820500Y-179700D01*
X821100Y-180100D01*
G01X835900Y-176900D02*
Y-184900D01*
G01X834500Y-179567D02*
X837300D01*
G01X842200Y-184900D02*
Y-176900D01*
G01Y-180767D02*
X842700Y-180100D01*
X843200Y-179700D01*
X844000Y-179567D01*
X844600Y-179700D01*
X845300Y-180233D01*
X845600Y-181033D01*
Y-184900D01*
G01X853700D02*
Y-179567D01*
G01Y-180500D02*
X853300Y-179967D01*
X852700Y-179700D01*
X852000Y-179567D01*
X851300Y-179833D01*
X850700Y-180367D01*
X850300Y-181167D01*
X850100Y-182233D01*
X850300Y-183300D01*
X850700Y-184100D01*
X851300Y-184633D01*
X852000Y-184900D01*
X852700Y-184767D01*
X853300Y-184367D01*
X853700Y-183834D01*
G01X858200Y-184900D02*
Y-179567D01*
G01Y-180900D02*
X858600Y-180233D01*
X859200Y-179700D01*
X860000Y-179567D01*
X860700Y-179700D01*
X861300Y-180233D01*
X861600Y-181167D01*
Y-184900D01*
G01X875900D02*
Y-176900D01*
X874700Y-178500D01*
G01Y-184900D02*
X877100D01*
G01X888900D02*
Y-179567D01*
G01Y-181033D02*
X889200Y-180367D01*
X889700Y-179833D01*
X890400Y-179567D01*
X891100Y-179833D01*
X891600Y-180367D01*
X891900Y-181033D01*
Y-184900D01*
G01Y-181033D02*
X892200Y-180367D01*
X892700Y-179833D01*
X893400Y-179567D01*
X894100Y-179833D01*
X894600Y-180367D01*
X894900Y-181167D01*
Y-184900D01*
G01X899900Y-179567D02*
Y-184900D01*
G01Y-177433D02*
X899700Y-177300D01*
Y-177033D01*
X899900Y-176900D01*
X900100Y-177033D01*
Y-177300D01*
X899900Y-177433D01*
G01X907900Y-184900D02*
Y-176900D01*
G01X915700Y-186367D02*
X916100Y-184633D01*
G01X930100Y-187567D02*
Y-179567D01*
G01Y-180767D02*
X930600Y-180100D01*
X931100Y-179700D01*
X931900Y-179567D01*
X932600Y-179700D01*
X933300Y-180367D01*
X933600Y-181300D01*
X933700Y-182233D01*
X933600Y-183167D01*
X933300Y-184100D01*
X932700Y-184633D01*
X931900Y-184900D01*
X931200Y-184767D01*
X930500Y-184367D01*
X930100Y-183834D01*
G01X939900Y-184900D02*
Y-176900D01*
G01X946400Y-181300D02*
X949600D01*
X949300Y-180367D01*
X948800Y-179833D01*
X948100Y-179567D01*
X947400Y-179700D01*
X946800Y-180100D01*
X946400Y-181033D01*
X946200Y-181834D01*
Y-182633D01*
X946400Y-183433D01*
X946900Y-184233D01*
X947500Y-184767D01*
X948200Y-184900D01*
X948900Y-184633D01*
X949600Y-183834D01*
G01X957700Y-184900D02*
Y-179567D01*
G01Y-180500D02*
X957300Y-179967D01*
X956700Y-179700D01*
X956000Y-179567D01*
X955300Y-179833D01*
X954700Y-180367D01*
X954300Y-181167D01*
X954100Y-182233D01*
X954300Y-183300D01*
X954700Y-184100D01*
X955300Y-184633D01*
X956000Y-184900D01*
X956700Y-184767D01*
X957300Y-184367D01*
X957700Y-183834D01*
G01X962400Y-183967D02*
X962900Y-184500D01*
X963600Y-184900D01*
X964200D01*
X964800Y-184633D01*
X965200Y-184233D01*
X965400Y-183700D01*
X965300Y-182900D01*
X964900Y-182500D01*
X963100Y-181700D01*
X962700Y-180767D01*
X962900Y-180100D01*
X963300Y-179700D01*
X963900Y-179567D01*
X964500Y-179700D01*
X965100Y-180100D01*
G01X970400Y-181300D02*
X973600D01*
X973300Y-180367D01*
X972800Y-179833D01*
X972100Y-179567D01*
X971400Y-179700D01*
X970800Y-180100D01*
X970400Y-181033D01*
X970200Y-181834D01*
Y-182633D01*
X970400Y-183433D01*
X970900Y-184233D01*
X971500Y-184767D01*
X972200Y-184900D01*
X972900Y-184633D01*
X973600Y-183834D01*
G01X987300Y-184900D02*
Y-178100D01*
X987500Y-177433D01*
X987900Y-177033D01*
X988500Y-176900D01*
X989100Y-177167D01*
X989400Y-177833D01*
G01X988200Y-180100D02*
X986200D01*
G01X995900Y-184900D02*
X995300Y-184767D01*
X994700Y-184233D01*
X994300Y-183300D01*
X994100Y-182233D01*
X994300Y-181167D01*
X994700Y-180233D01*
X995300Y-179700D01*
X995900Y-179567D01*
X996500Y-179700D01*
X997100Y-180233D01*
X997500Y-181167D01*
X997600Y-182233D01*
X997500Y-183300D01*
X997100Y-184233D01*
X996500Y-184767D01*
X995900Y-184900D01*
G01X1003900D02*
Y-176900D01*
G01X1011900Y-184900D02*
Y-176900D01*
G01X1019900Y-184900D02*
X1019300Y-184767D01*
X1018700Y-184233D01*
X1018300Y-183300D01*
X1018100Y-182233D01*
X1018300Y-181167D01*
X1018700Y-180233D01*
X1019300Y-179700D01*
X1019900Y-179567D01*
X1020500Y-179700D01*
X1021100Y-180233D01*
X1021500Y-181167D01*
X1021600Y-182233D01*
X1021500Y-183300D01*
X1021100Y-184233D01*
X1020500Y-184767D01*
X1019900Y-184900D01*
G01X1025400Y-179567D02*
X1026600Y-184900D01*
X1027900Y-179567D01*
X1029200Y-184900D01*
X1030400Y-179567D01*
G01X1040900Y-184900D02*
Y-179567D01*
G01Y-181033D02*
X1041200Y-180367D01*
X1041700Y-179833D01*
X1042400Y-179567D01*
X1043100Y-179833D01*
X1043600Y-180367D01*
X1043900Y-181033D01*
Y-184900D01*
G01Y-181033D02*
X1044200Y-180367D01*
X1044700Y-179833D01*
X1045400Y-179567D01*
X1046100Y-179833D01*
X1046600Y-180367D01*
X1046900Y-181167D01*
Y-184900D01*
G01X1050400Y-181300D02*
X1053600D01*
X1053300Y-180367D01*
X1052800Y-179833D01*
X1052100Y-179567D01*
X1051400Y-179700D01*
X1050800Y-180100D01*
X1050400Y-181033D01*
X1050200Y-181834D01*
Y-182633D01*
X1050400Y-183433D01*
X1050900Y-184233D01*
X1051500Y-184767D01*
X1052200Y-184900D01*
X1052900Y-184633D01*
X1053600Y-183834D01*
G01X1061500Y-180233D02*
X1060800Y-179700D01*
X1060200Y-179567D01*
X1059400Y-179833D01*
X1058800Y-180367D01*
X1058400Y-181300D01*
X1058300Y-182233D01*
X1058400Y-183167D01*
X1058800Y-183967D01*
X1059400Y-184633D01*
X1060200Y-184900D01*
X1060900Y-184633D01*
X1061500Y-184100D01*
G01X1066200Y-184900D02*
Y-176900D01*
G01Y-180767D02*
X1066700Y-180100D01*
X1067200Y-179700D01*
X1068000Y-179567D01*
X1068600Y-179700D01*
X1069300Y-180233D01*
X1069600Y-181033D01*
Y-184900D01*
G01X1077700D02*
Y-179567D01*
G01Y-180500D02*
X1077300Y-179967D01*
X1076700Y-179700D01*
X1076000Y-179567D01*
X1075300Y-179833D01*
X1074700Y-180367D01*
X1074300Y-181167D01*
X1074100Y-182233D01*
X1074300Y-183300D01*
X1074700Y-184100D01*
X1075300Y-184633D01*
X1076000Y-184900D01*
X1076700Y-184767D01*
X1077300Y-184367D01*
X1077700Y-183834D01*
G01X1082200Y-184900D02*
Y-179567D01*
G01Y-180900D02*
X1082600Y-180233D01*
X1083200Y-179700D01*
X1084000Y-179567D01*
X1084700Y-179700D01*
X1085300Y-180233D01*
X1085600Y-181167D01*
Y-184900D01*
G01X1091900Y-179567D02*
Y-184900D01*
G01Y-177433D02*
X1091700Y-177300D01*
Y-177033D01*
X1091900Y-176900D01*
X1092100Y-177033D01*
Y-177300D01*
X1091900Y-177433D01*
G01X1101500Y-180233D02*
X1100800Y-179700D01*
X1100200Y-179567D01*
X1099400Y-179833D01*
X1098800Y-180367D01*
X1098400Y-181300D01*
X1098300Y-182233D01*
X1098400Y-183167D01*
X1098800Y-183967D01*
X1099400Y-184633D01*
X1100200Y-184900D01*
X1100900Y-184633D01*
X1101500Y-184100D01*
G01X1109700Y-184900D02*
Y-179567D01*
G01Y-180500D02*
X1109300Y-179967D01*
X1108700Y-179700D01*
X1108000Y-179567D01*
X1107300Y-179833D01*
X1106700Y-180367D01*
X1106300Y-181167D01*
X1106100Y-182233D01*
X1106300Y-183300D01*
X1106700Y-184100D01*
X1107300Y-184633D01*
X1108000Y-184900D01*
X1108700Y-184767D01*
X1109300Y-184367D01*
X1109700Y-183834D01*
G01X1115900Y-184900D02*
Y-176900D01*
G01X1133700D02*
Y-184900D01*
G01Y-183700D02*
X1133300Y-184367D01*
X1132700Y-184767D01*
X1132000Y-184900D01*
X1131200Y-184633D01*
X1130600Y-183967D01*
X1130200Y-183167D01*
X1130100Y-182233D01*
X1130200Y-181300D01*
X1130600Y-180500D01*
X1131200Y-179833D01*
X1132000Y-179567D01*
X1132700Y-179700D01*
X1133200Y-179967D01*
X1133700Y-180500D01*
G01X1138500Y-184900D02*
Y-179567D01*
G01Y-180633D02*
X1139000Y-180100D01*
X1139500Y-179700D01*
X1140200Y-179567D01*
X1140700Y-179700D01*
X1141300Y-180100D01*
G01X1149700Y-184900D02*
Y-179567D01*
G01Y-180500D02*
X1149300Y-179967D01*
X1148700Y-179700D01*
X1148000Y-179567D01*
X1147300Y-179833D01*
X1146700Y-180367D01*
X1146300Y-181167D01*
X1146100Y-182233D01*
X1146300Y-183300D01*
X1146700Y-184100D01*
X1147300Y-184633D01*
X1148000Y-184900D01*
X1148700Y-184767D01*
X1149300Y-184367D01*
X1149700Y-183834D01*
G01X1153400Y-179567D02*
X1154600Y-184900D01*
X1155900Y-179567D01*
X1157200Y-184900D01*
X1158400Y-179567D01*
G01X1163900D02*
Y-184900D01*
G01Y-177433D02*
X1163700Y-177300D01*
Y-177033D01*
X1163900Y-176900D01*
X1164100Y-177033D01*
Y-177300D01*
X1163900Y-177433D01*
G01X1170200Y-184900D02*
Y-179567D01*
G01Y-180900D02*
X1170600Y-180233D01*
X1171200Y-179700D01*
X1172000Y-179567D01*
X1172700Y-179700D01*
X1173300Y-180233D01*
X1173600Y-181167D01*
Y-184900D01*
G01X1178500Y-186900D02*
X1179200Y-187433D01*
X1180000Y-187567D01*
X1180700Y-187433D01*
X1181300Y-186767D01*
X1181700Y-185833D01*
Y-179567D01*
G01Y-180633D02*
X1181300Y-180100D01*
X1180700Y-179700D01*
X1180000Y-179567D01*
X1179200Y-179833D01*
X1178700Y-180367D01*
X1178300Y-181300D01*
X1178100Y-182233D01*
X1178200Y-183033D01*
X1178600Y-183967D01*
X1179200Y-184633D01*
X1180000Y-184900D01*
X1180600Y-184767D01*
X1181300Y-184233D01*
X1181700Y-183700D01*
G01X1187200Y-187300D02*
X1188600Y-185433D01*
Y-183567D01*
X1187200D01*
Y-185433D01*
X1188600D01*
G01Y-182233D02*
Y-180367D01*
X1187200D01*
Y-182233D01*
X1188600D01*
G01X321900Y-189200D02*
X324300D01*
G01X323100D02*
Y-197200D01*
G01X321900D02*
X324300D01*
G01X330500D02*
Y-190400D01*
X330700Y-189733D01*
X331100Y-189333D01*
X331700Y-189200D01*
X332300Y-189467D01*
X332600Y-190133D01*
G01X331400Y-192400D02*
X329400D01*
G01X347100Y-191867D02*
Y-197200D01*
G01Y-189733D02*
X346900Y-189600D01*
Y-189333D01*
X347100Y-189200D01*
X347300Y-189333D01*
Y-189600D01*
X347100Y-189733D01*
G01X353600Y-196267D02*
X354100Y-196800D01*
X354800Y-197200D01*
X355400D01*
X356000Y-196933D01*
X356400Y-196533D01*
X356600Y-196000D01*
X356500Y-195200D01*
X356100Y-194800D01*
X354300Y-194000D01*
X353900Y-193067D01*
X354100Y-192400D01*
X354500Y-192000D01*
X355100Y-191867D01*
X355700Y-192000D01*
X356300Y-192400D01*
G01X369700Y-199200D02*
X370400Y-199733D01*
X371200Y-199867D01*
X371900Y-199733D01*
X372500Y-199067D01*
X372900Y-198133D01*
Y-191867D01*
G01Y-192933D02*
X372500Y-192400D01*
X371900Y-192000D01*
X371200Y-191867D01*
X370400Y-192133D01*
X369900Y-192667D01*
X369500Y-193600D01*
X369300Y-194533D01*
X369400Y-195333D01*
X369800Y-196267D01*
X370400Y-196933D01*
X371200Y-197200D01*
X371800Y-197067D01*
X372500Y-196533D01*
X372900Y-196000D01*
G01X377700Y-197200D02*
Y-191867D01*
G01Y-192933D02*
X378200Y-192400D01*
X378700Y-192000D01*
X379400Y-191867D01*
X379900Y-192000D01*
X380500Y-192400D01*
G01X385600Y-193600D02*
X388800D01*
X388500Y-192667D01*
X388000Y-192133D01*
X387300Y-191867D01*
X386600Y-192000D01*
X386000Y-192400D01*
X385600Y-193333D01*
X385400Y-194134D01*
Y-194933D01*
X385600Y-195733D01*
X386100Y-196533D01*
X386700Y-197067D01*
X387400Y-197200D01*
X388100Y-196933D01*
X388800Y-196134D01*
G01X396900Y-197200D02*
Y-191867D01*
G01Y-192800D02*
X396500Y-192267D01*
X395900Y-192000D01*
X395200Y-191867D01*
X394500Y-192133D01*
X393900Y-192667D01*
X393500Y-193467D01*
X393300Y-194533D01*
X393500Y-195600D01*
X393900Y-196400D01*
X394500Y-196933D01*
X395200Y-197200D01*
X395900Y-197067D01*
X396500Y-196667D01*
X396900Y-196134D01*
G01X403100Y-189200D02*
Y-197200D01*
G01X401700Y-191867D02*
X404500D01*
G01X409600Y-193600D02*
X412800D01*
X412500Y-192667D01*
X412000Y-192133D01*
X411300Y-191867D01*
X410600Y-192000D01*
X410000Y-192400D01*
X409600Y-193333D01*
X409400Y-194134D01*
Y-194933D01*
X409600Y-195733D01*
X410100Y-196533D01*
X410700Y-197067D01*
X411400Y-197200D01*
X412100Y-196933D01*
X412800Y-196134D01*
G01X417700Y-197200D02*
Y-191867D01*
G01Y-192933D02*
X418200Y-192400D01*
X418700Y-192000D01*
X419400Y-191867D01*
X419900Y-192000D01*
X420500Y-192400D01*
G01X435100Y-189200D02*
Y-197200D01*
G01X433700Y-191867D02*
X436500D01*
G01X441400Y-197200D02*
Y-189200D01*
G01Y-193067D02*
X441900Y-192400D01*
X442400Y-192000D01*
X443200Y-191867D01*
X443800Y-192000D01*
X444500Y-192533D01*
X444800Y-193333D01*
Y-197200D01*
G01X452900D02*
Y-191867D01*
G01Y-192800D02*
X452500Y-192267D01*
X451900Y-192000D01*
X451200Y-191867D01*
X450500Y-192133D01*
X449900Y-192667D01*
X449500Y-193467D01*
X449300Y-194533D01*
X449500Y-195600D01*
X449900Y-196400D01*
X450500Y-196933D01*
X451200Y-197200D01*
X451900Y-197067D01*
X452500Y-196667D01*
X452900Y-196134D01*
G01X457400Y-197200D02*
Y-191867D01*
G01Y-193200D02*
X457800Y-192533D01*
X458400Y-192000D01*
X459200Y-191867D01*
X459900Y-192000D01*
X460500Y-192533D01*
X460800Y-193467D01*
Y-197200D01*
G01X475100D02*
Y-189200D01*
X473900Y-190800D01*
G01Y-197200D02*
X476300D01*
G01X488100D02*
Y-191867D01*
G01Y-193333D02*
X488400Y-192667D01*
X488900Y-192133D01*
X489600Y-191867D01*
X490300Y-192133D01*
X490800Y-192667D01*
X491100Y-193333D01*
Y-197200D01*
G01Y-193333D02*
X491400Y-192667D01*
X491900Y-192133D01*
X492600Y-191867D01*
X493300Y-192133D01*
X493800Y-192667D01*
X494100Y-193467D01*
Y-197200D01*
G01X499100Y-191867D02*
Y-197200D01*
G01Y-189733D02*
X498900Y-189600D01*
Y-189333D01*
X499100Y-189200D01*
X499300Y-189333D01*
Y-189600D01*
X499100Y-189733D01*
G01X505600Y-196267D02*
X506100Y-196800D01*
X506800Y-197200D01*
X507400D01*
X508000Y-196933D01*
X508400Y-196533D01*
X508600Y-196000D01*
X508500Y-195200D01*
X508100Y-194800D01*
X506300Y-194000D01*
X505900Y-193067D01*
X506100Y-192400D01*
X506500Y-192000D01*
X507100Y-191867D01*
X507700Y-192000D01*
X508300Y-192400D01*
G01X514900Y-198667D02*
X515300Y-196933D01*
G01X529300Y-199867D02*
Y-191867D01*
G01Y-193067D02*
X529800Y-192400D01*
X530300Y-192000D01*
X531100Y-191867D01*
X531800Y-192000D01*
X532500Y-192667D01*
X532800Y-193600D01*
X532900Y-194533D01*
X532800Y-195467D01*
X532500Y-196400D01*
X531900Y-196933D01*
X531100Y-197200D01*
X530400Y-197067D01*
X529700Y-196667D01*
X529300Y-196134D01*
G01X539100Y-197200D02*
Y-189200D01*
G01X545600Y-193600D02*
X548800D01*
X548500Y-192667D01*
X548000Y-192133D01*
X547300Y-191867D01*
X546600Y-192000D01*
X546000Y-192400D01*
X545600Y-193333D01*
X545400Y-194134D01*
Y-194933D01*
X545600Y-195733D01*
X546100Y-196533D01*
X546700Y-197067D01*
X547400Y-197200D01*
X548100Y-196933D01*
X548800Y-196134D01*
G01X556900Y-197200D02*
Y-191867D01*
G01Y-192800D02*
X556500Y-192267D01*
X555900Y-192000D01*
X555200Y-191867D01*
X554500Y-192133D01*
X553900Y-192667D01*
X553500Y-193467D01*
X553300Y-194533D01*
X553500Y-195600D01*
X553900Y-196400D01*
X554500Y-196933D01*
X555200Y-197200D01*
X555900Y-197067D01*
X556500Y-196667D01*
X556900Y-196134D01*
G01X561600Y-196267D02*
X562100Y-196800D01*
X562800Y-197200D01*
X563400D01*
X564000Y-196933D01*
X564400Y-196533D01*
X564600Y-196000D01*
X564500Y-195200D01*
X564100Y-194800D01*
X562300Y-194000D01*
X561900Y-193067D01*
X562100Y-192400D01*
X562500Y-192000D01*
X563100Y-191867D01*
X563700Y-192000D01*
X564300Y-192400D01*
G01X569600Y-193600D02*
X572800D01*
X572500Y-192667D01*
X572000Y-192133D01*
X571300Y-191867D01*
X570600Y-192000D01*
X570000Y-192400D01*
X569600Y-193333D01*
X569400Y-194134D01*
Y-194933D01*
X569600Y-195733D01*
X570100Y-196533D01*
X570700Y-197067D01*
X571400Y-197200D01*
X572100Y-196933D01*
X572800Y-196134D01*
G01X587100Y-191867D02*
Y-197200D01*
G01Y-189733D02*
X586900Y-189600D01*
Y-189333D01*
X587100Y-189200D01*
X587300Y-189333D01*
Y-189600D01*
X587100Y-189733D01*
G01X593600Y-196267D02*
X594100Y-196800D01*
X594800Y-197200D01*
X595400D01*
X596000Y-196933D01*
X596400Y-196533D01*
X596600Y-196000D01*
X596500Y-195200D01*
X596100Y-194800D01*
X594300Y-194000D01*
X593900Y-193067D01*
X594100Y-192400D01*
X594500Y-192000D01*
X595100Y-191867D01*
X595700Y-192000D01*
X596300Y-192400D01*
G01X601600Y-196267D02*
X602100Y-196800D01*
X602800Y-197200D01*
X603400D01*
X604000Y-196933D01*
X604400Y-196533D01*
X604600Y-196000D01*
X604500Y-195200D01*
X604100Y-194800D01*
X602300Y-194000D01*
X601900Y-193067D01*
X602100Y-192400D01*
X602500Y-192000D01*
X603100Y-191867D01*
X603700Y-192000D01*
X604300Y-192400D01*
G01X609400Y-191867D02*
Y-195600D01*
X609800Y-196533D01*
X610400Y-197067D01*
X611100Y-197200D01*
X611800Y-197067D01*
X612400Y-196533D01*
X612800Y-195600D01*
G01Y-197200D02*
Y-191867D01*
G01X617600Y-193600D02*
X620800D01*
X620500Y-192667D01*
X620000Y-192133D01*
X619300Y-191867D01*
X618600Y-192000D01*
X618000Y-192400D01*
X617600Y-193333D01*
X617400Y-194134D01*
Y-194933D01*
X617600Y-195733D01*
X618100Y-196533D01*
X618700Y-197067D01*
X619400Y-197200D01*
X620100Y-196933D01*
X620800Y-196134D01*
G01X633600Y-193600D02*
X636800D01*
X636500Y-192667D01*
X636000Y-192133D01*
X635300Y-191867D01*
X634600Y-192000D01*
X634000Y-192400D01*
X633600Y-193333D01*
X633400Y-194134D01*
Y-194933D01*
X633600Y-195733D01*
X634100Y-196533D01*
X634700Y-197067D01*
X635400Y-197200D01*
X636100Y-196933D01*
X636800Y-196134D01*
G01X641400Y-197200D02*
Y-191867D01*
G01Y-193200D02*
X641800Y-192533D01*
X642400Y-192000D01*
X643200Y-191867D01*
X643900Y-192000D01*
X644500Y-192533D01*
X644800Y-193467D01*
Y-197200D01*
G01X649700Y-199200D02*
X650400Y-199733D01*
X651200Y-199867D01*
X651900Y-199733D01*
X652500Y-199067D01*
X652900Y-198133D01*
Y-191867D01*
G01Y-192933D02*
X652500Y-192400D01*
X651900Y-192000D01*
X651200Y-191867D01*
X650400Y-192133D01*
X649900Y-192667D01*
X649500Y-193600D01*
X649300Y-194533D01*
X649400Y-195333D01*
X649800Y-196267D01*
X650400Y-196933D01*
X651200Y-197200D01*
X651800Y-197067D01*
X652500Y-196533D01*
X652900Y-196000D01*
G01X659100Y-191867D02*
Y-197200D01*
G01Y-189733D02*
X658900Y-189600D01*
Y-189333D01*
X659100Y-189200D01*
X659300Y-189333D01*
Y-189600D01*
X659100Y-189733D01*
G01X665400Y-197200D02*
Y-191867D01*
G01Y-193200D02*
X665800Y-192533D01*
X666400Y-192000D01*
X667200Y-191867D01*
X667900Y-192000D01*
X668500Y-192533D01*
X668800Y-193467D01*
Y-197200D01*
G01X673600Y-193600D02*
X676800D01*
X676500Y-192667D01*
X676000Y-192133D01*
X675300Y-191867D01*
X674600Y-192000D01*
X674000Y-192400D01*
X673600Y-193333D01*
X673400Y-194134D01*
Y-194933D01*
X673600Y-195733D01*
X674100Y-196533D01*
X674700Y-197067D01*
X675400Y-197200D01*
X676100Y-196933D01*
X676800Y-196134D01*
G01X681600Y-193600D02*
X684800D01*
X684500Y-192667D01*
X684000Y-192133D01*
X683300Y-191867D01*
X682600Y-192000D01*
X682000Y-192400D01*
X681600Y-193333D01*
X681400Y-194134D01*
Y-194933D01*
X681600Y-195733D01*
X682100Y-196533D01*
X682700Y-197067D01*
X683400Y-197200D01*
X684100Y-196933D01*
X684800Y-196134D01*
G01X689700Y-197200D02*
Y-191867D01*
G01Y-192933D02*
X690200Y-192400D01*
X690700Y-192000D01*
X691400Y-191867D01*
X691900Y-192000D01*
X692500Y-192400D01*
G01X699100Y-191867D02*
Y-197200D01*
G01Y-189733D02*
X698900Y-189600D01*
Y-189333D01*
X699100Y-189200D01*
X699300Y-189333D01*
Y-189600D01*
X699100Y-189733D01*
G01X705400Y-197200D02*
Y-191867D01*
G01Y-193200D02*
X705800Y-192533D01*
X706400Y-192000D01*
X707200Y-191867D01*
X707900Y-192000D01*
X708500Y-192533D01*
X708800Y-193467D01*
Y-197200D01*
G01X713700Y-199200D02*
X714400Y-199733D01*
X715200Y-199867D01*
X715900Y-199733D01*
X716500Y-199067D01*
X716900Y-198133D01*
Y-191867D01*
G01Y-192933D02*
X716500Y-192400D01*
X715900Y-192000D01*
X715200Y-191867D01*
X714400Y-192133D01*
X713900Y-192667D01*
X713500Y-193600D01*
X713300Y-194533D01*
X713400Y-195333D01*
X713800Y-196267D01*
X714400Y-196933D01*
X715200Y-197200D01*
X715800Y-197067D01*
X716500Y-196533D01*
X716900Y-196000D01*
G01X732900Y-199867D02*
Y-191867D01*
G01Y-193067D02*
X732400Y-192400D01*
X731800Y-192000D01*
X731100Y-191867D01*
X730500Y-192000D01*
X729800Y-192667D01*
X729400Y-193600D01*
X729300Y-194533D01*
X729400Y-195467D01*
X729800Y-196400D01*
X730500Y-197067D01*
X731100Y-197200D01*
X731800Y-197067D01*
X732400Y-196667D01*
X732900Y-196000D01*
G01X737400Y-191867D02*
Y-195600D01*
X737800Y-196533D01*
X738400Y-197067D01*
X739100Y-197200D01*
X739800Y-197067D01*
X740400Y-196533D01*
X740800Y-195600D01*
G01Y-197200D02*
Y-191867D01*
G01X745600Y-193600D02*
X748800D01*
X748500Y-192667D01*
X748000Y-192133D01*
X747300Y-191867D01*
X746600Y-192000D01*
X746000Y-192400D01*
X745600Y-193333D01*
X745400Y-194134D01*
Y-194933D01*
X745600Y-195733D01*
X746100Y-196533D01*
X746700Y-197067D01*
X747400Y-197200D01*
X748100Y-196933D01*
X748800Y-196134D01*
G01X753700Y-197200D02*
Y-191867D01*
G01Y-192933D02*
X754200Y-192400D01*
X754700Y-192000D01*
X755400Y-191867D01*
X755900Y-192000D01*
X756500Y-192400D01*
G01X761000Y-199600D02*
X761600Y-199867D01*
X762400Y-199600D01*
X762900Y-199067D01*
X763300Y-198400D01*
X763900Y-196267D01*
X765200Y-191867D01*
G01X762000D02*
X763900Y-196267D01*
G01X771100Y-197467D02*
X770900Y-197333D01*
Y-197067D01*
X771100Y-196933D01*
X771300Y-197067D01*
Y-197333D01*
X771100Y-197467D01*
G01X321500Y-165100D02*
Y-170833D01*
X321900Y-172034D01*
X322700Y-172833D01*
X323700Y-173100D01*
X324700Y-172833D01*
X325500Y-172034D01*
X325900Y-170833D01*
Y-165100D01*
G01X330000Y-173100D02*
Y-167767D01*
G01Y-169100D02*
X330400Y-168433D01*
X331000Y-167900D01*
X331800Y-167767D01*
X332500Y-167900D01*
X333100Y-168433D01*
X333400Y-169367D01*
Y-173100D01*
G01X339700Y-167767D02*
Y-173100D01*
G01Y-165633D02*
X339500Y-165500D01*
Y-165233D01*
X339700Y-165100D01*
X339900Y-165233D01*
Y-165500D01*
X339700Y-165633D01*
G01X347700Y-165100D02*
Y-173100D01*
G01X346300Y-167767D02*
X349100D01*
G01X365300Y-168433D02*
X364600Y-167900D01*
X364000Y-167767D01*
X363200Y-168033D01*
X362600Y-168567D01*
X362200Y-169500D01*
X362100Y-170433D01*
X362200Y-171367D01*
X362600Y-172167D01*
X363200Y-172833D01*
X364000Y-173100D01*
X364700Y-172833D01*
X365300Y-172300D01*
G01X371700Y-173100D02*
X371100Y-172967D01*
X370500Y-172433D01*
X370100Y-171500D01*
X369900Y-170433D01*
X370100Y-169367D01*
X370500Y-168433D01*
X371100Y-167900D01*
X371700Y-167767D01*
X372300Y-167900D01*
X372900Y-168433D01*
X373300Y-169367D01*
X373400Y-170433D01*
X373300Y-171500D01*
X372900Y-172433D01*
X372300Y-172967D01*
X371700Y-173100D01*
G01X378000D02*
Y-167767D01*
G01Y-169100D02*
X378400Y-168433D01*
X379000Y-167900D01*
X379800Y-167767D01*
X380500Y-167900D01*
X381100Y-168433D01*
X381400Y-169367D01*
Y-173100D01*
G01X385900Y-167767D02*
X387700Y-173100D01*
X389500Y-167767D01*
G01X394200Y-169500D02*
X397400D01*
X397100Y-168567D01*
X396600Y-168033D01*
X395900Y-167767D01*
X395200Y-167900D01*
X394600Y-168300D01*
X394200Y-169233D01*
X394000Y-170034D01*
Y-170833D01*
X394200Y-171633D01*
X394700Y-172433D01*
X395300Y-172967D01*
X396000Y-173100D01*
X396700Y-172833D01*
X397400Y-172034D01*
G01X402300Y-173100D02*
Y-167767D01*
G01Y-168833D02*
X402800Y-168300D01*
X403300Y-167900D01*
X404000Y-167767D01*
X404500Y-167900D01*
X405100Y-168300D01*
G01X410200Y-172167D02*
X410700Y-172700D01*
X411400Y-173100D01*
X412000D01*
X412600Y-172833D01*
X413000Y-172433D01*
X413200Y-171900D01*
X413100Y-171100D01*
X412700Y-170700D01*
X410900Y-169900D01*
X410500Y-168967D01*
X410700Y-168300D01*
X411100Y-167900D01*
X411700Y-167767D01*
X412300Y-167900D01*
X412900Y-168300D01*
G01X419700Y-167767D02*
Y-173100D01*
G01Y-165633D02*
X419500Y-165500D01*
Y-165233D01*
X419700Y-165100D01*
X419900Y-165233D01*
Y-165500D01*
X419700Y-165633D01*
G01X427700Y-173100D02*
X427100Y-172967D01*
X426500Y-172433D01*
X426100Y-171500D01*
X425900Y-170433D01*
X426100Y-169367D01*
X426500Y-168433D01*
X427100Y-167900D01*
X427700Y-167767D01*
X428300Y-167900D01*
X428900Y-168433D01*
X429300Y-169367D01*
X429400Y-170433D01*
X429300Y-171500D01*
X428900Y-172433D01*
X428300Y-172967D01*
X427700Y-173100D01*
G01X434000D02*
Y-167767D01*
G01Y-169100D02*
X434400Y-168433D01*
X435000Y-167900D01*
X435800Y-167767D01*
X436500Y-167900D01*
X437100Y-168433D01*
X437400Y-169367D01*
Y-173100D01*
G01X451700Y-167767D02*
Y-173100D01*
G01Y-165633D02*
X451500Y-165500D01*
Y-165233D01*
X451700Y-165100D01*
X451900Y-165233D01*
Y-165500D01*
X451700Y-165633D01*
G01X458200Y-172167D02*
X458700Y-172700D01*
X459400Y-173100D01*
X460000D01*
X460600Y-172833D01*
X461000Y-172433D01*
X461200Y-171900D01*
X461100Y-171100D01*
X460700Y-170700D01*
X458900Y-169900D01*
X458500Y-168967D01*
X458700Y-168300D01*
X459100Y-167900D01*
X459700Y-167767D01*
X460300Y-167900D01*
X460900Y-168300D01*
G01X466200Y-172167D02*
X466700Y-172700D01*
X467400Y-173100D01*
X468000D01*
X468600Y-172833D01*
X469000Y-172433D01*
X469200Y-171900D01*
X469100Y-171100D01*
X468700Y-170700D01*
X466900Y-169900D01*
X466500Y-168967D01*
X466700Y-168300D01*
X467100Y-167900D01*
X467700Y-167767D01*
X468300Y-167900D01*
X468900Y-168300D01*
G01X474000Y-167767D02*
Y-171500D01*
X474400Y-172433D01*
X475000Y-172967D01*
X475700Y-173100D01*
X476400Y-172967D01*
X477000Y-172433D01*
X477400Y-171500D01*
G01Y-173100D02*
Y-167767D01*
G01X482200Y-169500D02*
X485400D01*
X485100Y-168567D01*
X484600Y-168033D01*
X483900Y-167767D01*
X483200Y-167900D01*
X482600Y-168300D01*
X482200Y-169233D01*
X482000Y-170034D01*
Y-170833D01*
X482200Y-171633D01*
X482700Y-172433D01*
X483300Y-172967D01*
X484000Y-173100D01*
X484700Y-172833D01*
X485400Y-172034D01*
G01X491700Y-173367D02*
X491500Y-173233D01*
Y-172967D01*
X491700Y-172833D01*
X491900Y-172967D01*
Y-173233D01*
X491700Y-173367D01*
G01Y-169767D02*
X491500Y-169633D01*
Y-169367D01*
X491700Y-169233D01*
X491900Y-169367D01*
Y-169633D01*
X491700Y-169767D01*
G01X322300Y32000D02*
Y40000D01*
X326900Y32000D01*
Y40000D01*
G01X332600Y32000D02*
X331800Y32133D01*
X331100Y32667D01*
X330500Y33467D01*
X330100Y34400D01*
X329900Y35467D01*
Y36533D01*
X330100Y37600D01*
X330500Y38533D01*
X331100Y39333D01*
X331800Y39867D01*
X332600Y40000D01*
X333400Y39867D01*
X334100Y39333D01*
X334700Y38533D01*
X335100Y37600D01*
X335300Y36533D01*
Y35467D01*
X335100Y34400D01*
X334700Y33467D01*
X334100Y32667D01*
X333400Y32133D01*
X332600Y32000D01*
G01X340600Y31733D02*
X340400Y31867D01*
Y32133D01*
X340600Y32267D01*
X340800Y32133D01*
Y31867D01*
X340600Y31733D01*
G01X331701Y-121500D02*
Y-113500D01*
X330501Y-115100D01*
G01Y-121500D02*
X332901D01*
G01X337801Y-114833D02*
X338401Y-114033D01*
X339101Y-113633D01*
X339901Y-113500D01*
X340901Y-113767D01*
X341601Y-114433D01*
X341801Y-115233D01*
X341701Y-116034D01*
X341301Y-116700D01*
X339301Y-118033D01*
X338401Y-118967D01*
X337801Y-120300D01*
X337601Y-121500D01*
X341801D01*
G01X331727Y-109000D02*
Y-101000D01*
X330527Y-102600D01*
G01Y-109000D02*
X332927D01*
G01X339727D02*
Y-101000D01*
X338527Y-102600D01*
G01Y-109000D02*
X340927D01*
G01X331100Y-96000D02*
Y-88000D01*
X329900Y-89600D01*
G01Y-96000D02*
X332300D01*
G01X339100Y-88000D02*
X338300Y-88267D01*
X337700Y-88933D01*
X337300Y-89733D01*
X337000Y-90800D01*
X336900Y-92000D01*
X337000Y-93200D01*
X337300Y-94267D01*
X337700Y-95067D01*
X338300Y-95733D01*
X339100Y-96000D01*
X339900Y-95733D01*
X340500Y-95067D01*
X340900Y-94267D01*
X341200Y-93200D01*
X341300Y-92000D01*
X341200Y-90800D01*
X340900Y-89733D01*
X340500Y-88933D01*
X339900Y-88267D01*
X339100Y-88000D01*
G01X329400Y-82567D02*
X330100Y-83233D01*
X330900Y-83500D01*
X331700Y-83233D01*
X332400Y-82434D01*
X332900Y-81233D01*
X333100Y-80033D01*
Y-78567D01*
X332900Y-77367D01*
X332400Y-76300D01*
X331800Y-75767D01*
X331100Y-75500D01*
X330300Y-75767D01*
X329700Y-76300D01*
X329300Y-77100D01*
X329100Y-78167D01*
X329300Y-79100D01*
X329800Y-80033D01*
X330400Y-80567D01*
X331100Y-80700D01*
X331900Y-80434D01*
X332500Y-79767D01*
X333100Y-78567D01*
G01X331100Y-71500D02*
X331800Y-71367D01*
X332600Y-70967D01*
X333100Y-70300D01*
X333300Y-69367D01*
X333100Y-68434D01*
X332500Y-67633D01*
X331600Y-67233D01*
X330600D01*
X330000Y-66967D01*
X329500Y-66300D01*
X329300Y-65367D01*
X329600Y-64433D01*
X330300Y-63767D01*
X331100Y-63500D01*
X331900Y-63767D01*
X332600Y-64433D01*
X332900Y-65367D01*
X332700Y-66300D01*
X332200Y-66967D01*
X331600Y-67233D01*
X330600D01*
X329700Y-67633D01*
X329100Y-68434D01*
X328900Y-69367D01*
X329100Y-70300D01*
X329600Y-70967D01*
X330400Y-71367D01*
X331100Y-71500D01*
G01X331400Y-58500D02*
X331600Y-56767D01*
X331900Y-55300D01*
X332300Y-53967D01*
X332800Y-52500D01*
X333600Y-50500D01*
X329600D01*
G01X329700Y-42995D02*
X330400Y-42061D01*
X331000Y-41528D01*
X331800Y-41261D01*
X332500Y-41528D01*
X333000Y-42061D01*
X333400Y-42861D01*
X333500Y-43795D01*
X333400Y-44595D01*
X333000Y-45395D01*
X332400Y-46061D01*
X331700Y-46328D01*
X330900Y-46061D01*
X330200Y-45262D01*
X329800Y-44061D01*
X329700Y-42728D01*
X329900Y-40995D01*
X330200Y-40061D01*
X330700Y-39128D01*
X331400Y-38461D01*
X332100Y-38328D01*
X332800Y-38595D01*
X333300Y-39261D01*
G01X329400Y-31800D02*
X330000Y-32467D01*
X330700Y-32867D01*
X331600Y-33000D01*
X332500Y-32733D01*
X333200Y-32200D01*
X333700Y-31267D01*
X333800Y-30200D01*
X333600Y-29133D01*
X333100Y-28467D01*
X332400Y-27933D01*
X331700Y-27800D01*
X331000Y-27933D01*
X330100Y-28467D01*
X330400Y-25000D01*
X333100D01*
G01X332800Y-21500D02*
Y-13500D01*
X329100Y-19233D01*
X334100D01*
G01X329900Y-6900D02*
X330500Y-7833D01*
X331300Y-8367D01*
X332200Y-8500D01*
X333000Y-8367D01*
X333800Y-7700D01*
X334300Y-6900D01*
X334400Y-6100D01*
X334200Y-5167D01*
X333500Y-4500D01*
X332800Y-4233D01*
X331900D01*
G01X332800D02*
X333400Y-3833D01*
X333900Y-3167D01*
X334100Y-2367D01*
X333900Y-1567D01*
X333400Y-900D01*
X332500Y-500D01*
X331600Y-633D01*
X330700Y-1167D01*
G01X330200Y10667D02*
X330800Y11467D01*
X331500Y11867D01*
X332300Y12000D01*
X333300Y11733D01*
X334000Y11067D01*
X334200Y10267D01*
X334100Y9466D01*
X333700Y8800D01*
X331700Y7467D01*
X330800Y6533D01*
X330200Y5200D01*
X330000Y4000D01*
X334200D01*
G01X332100Y16500D02*
Y24500D01*
X330900Y22900D01*
G01Y16500D02*
X333300D01*
G01X356229Y16000D02*
Y24000D01*
G01X360429D02*
Y16000D01*
G01Y20000D02*
X356229D01*
G01X366329Y16000D02*
X365729Y16133D01*
X365129Y16667D01*
X364729Y17600D01*
X364529Y18667D01*
X364729Y19733D01*
X365129Y20667D01*
X365729Y21200D01*
X366329Y21333D01*
X366929Y21200D01*
X367529Y20667D01*
X367929Y19733D01*
X368029Y18667D01*
X367929Y17600D01*
X367529Y16667D01*
X366929Y16133D01*
X366329Y16000D01*
G01X374329D02*
Y24000D01*
G01X380829Y19600D02*
X384029D01*
X383729Y20533D01*
X383229Y21067D01*
X382529Y21333D01*
X381829Y21200D01*
X381229Y20800D01*
X380829Y19867D01*
X380629Y19066D01*
Y18267D01*
X380829Y17467D01*
X381329Y16667D01*
X381929Y16133D01*
X382629Y16000D01*
X383329Y16267D01*
X384029Y17066D01*
G01X364100Y-121000D02*
Y-113000D01*
X366600D01*
X367400Y-113400D01*
X367900Y-113933D01*
X368100Y-115000D01*
X367900Y-116067D01*
X367300Y-116733D01*
X366600Y-117133D01*
X364100D01*
G01X366600D02*
X368100Y-121000D01*
G01X374100D02*
X373500Y-120867D01*
X372900Y-120333D01*
X372500Y-119400D01*
X372300Y-118333D01*
X372500Y-117267D01*
X372900Y-116333D01*
X373500Y-115800D01*
X374100Y-115667D01*
X374700Y-115800D01*
X375300Y-116333D01*
X375700Y-117267D01*
X375800Y-118333D01*
X375700Y-119400D01*
X375300Y-120333D01*
X374700Y-120867D01*
X374100Y-121000D01*
G01X380400Y-115667D02*
Y-119400D01*
X380800Y-120333D01*
X381400Y-120867D01*
X382100Y-121000D01*
X382800Y-120867D01*
X383400Y-120333D01*
X383800Y-119400D01*
G01Y-121000D02*
Y-115667D01*
G01X388700Y-123000D02*
X389400Y-123533D01*
X390200Y-123667D01*
X390900Y-123533D01*
X391500Y-122867D01*
X391900Y-121933D01*
Y-115667D01*
G01Y-116733D02*
X391500Y-116200D01*
X390900Y-115800D01*
X390200Y-115667D01*
X389400Y-115933D01*
X388900Y-116467D01*
X388500Y-117400D01*
X388300Y-118333D01*
X388400Y-119133D01*
X388800Y-120067D01*
X389400Y-120733D01*
X390200Y-121000D01*
X390800Y-120867D01*
X391500Y-120333D01*
X391900Y-119800D01*
G01X396400Y-121000D02*
Y-113000D01*
G01Y-116867D02*
X396900Y-116200D01*
X397400Y-115800D01*
X398200Y-115667D01*
X398800Y-115800D01*
X399500Y-116333D01*
X399800Y-117133D01*
Y-121000D01*
G01X404400D02*
Y-115667D01*
G01Y-117000D02*
X404800Y-116333D01*
X405400Y-115800D01*
X406200Y-115667D01*
X406900Y-115800D01*
X407500Y-116333D01*
X407800Y-117267D01*
Y-121000D01*
G01X412600Y-117400D02*
X415800D01*
X415500Y-116467D01*
X415000Y-115933D01*
X414300Y-115667D01*
X413600Y-115800D01*
X413000Y-116200D01*
X412600Y-117133D01*
X412400Y-117934D01*
Y-118733D01*
X412600Y-119533D01*
X413100Y-120333D01*
X413700Y-120867D01*
X414400Y-121000D01*
X415100Y-120733D01*
X415800Y-119934D01*
G01X420600Y-120067D02*
X421100Y-120600D01*
X421800Y-121000D01*
X422400D01*
X423000Y-120733D01*
X423400Y-120333D01*
X423600Y-119800D01*
X423500Y-119000D01*
X423100Y-118600D01*
X421300Y-117800D01*
X420900Y-116867D01*
X421100Y-116200D01*
X421500Y-115800D01*
X422100Y-115667D01*
X422700Y-115800D01*
X423300Y-116200D01*
G01X428600Y-120067D02*
X429100Y-120600D01*
X429800Y-121000D01*
X430400D01*
X431000Y-120733D01*
X431400Y-120333D01*
X431600Y-119800D01*
X431500Y-119000D01*
X431100Y-118600D01*
X429300Y-117800D01*
X428900Y-116867D01*
X429100Y-116200D01*
X429500Y-115800D01*
X430100Y-115667D01*
X430700Y-115800D01*
X431300Y-116200D01*
G01X360500Y-54000D02*
Y-46000D01*
G01X364700D02*
Y-54000D01*
G01Y-50000D02*
X360500D01*
G01X370600Y-54000D02*
X370000Y-53867D01*
X369400Y-53333D01*
X369000Y-52400D01*
X368800Y-51333D01*
X369000Y-50267D01*
X369400Y-49333D01*
X370000Y-48800D01*
X370600Y-48667D01*
X371200Y-48800D01*
X371800Y-49333D01*
X372200Y-50267D01*
X372300Y-51333D01*
X372200Y-52400D01*
X371800Y-53333D01*
X371200Y-53867D01*
X370600Y-54000D01*
G01X378600D02*
Y-46000D01*
G01X385100Y-50400D02*
X388300D01*
X388000Y-49467D01*
X387500Y-48933D01*
X386800Y-48667D01*
X386100Y-48800D01*
X385500Y-49200D01*
X385100Y-50133D01*
X384900Y-50934D01*
Y-51733D01*
X385100Y-52533D01*
X385600Y-53333D01*
X386200Y-53867D01*
X386900Y-54000D01*
X387600Y-53733D01*
X388300Y-52934D01*
G01X379400Y-223600D02*
Y-231600D01*
G01X377100Y-223600D02*
X381700D01*
G01X385700Y-231600D02*
Y-223600D01*
G01Y-227467D02*
X386200Y-226800D01*
X386700Y-226400D01*
X387500Y-226267D01*
X388100Y-226400D01*
X388800Y-226933D01*
X389100Y-227733D01*
Y-231600D01*
G01X393900Y-228000D02*
X397100D01*
X396800Y-227067D01*
X396300Y-226533D01*
X395600Y-226267D01*
X394900Y-226400D01*
X394300Y-226800D01*
X393900Y-227733D01*
X393700Y-228534D01*
Y-229333D01*
X393900Y-230133D01*
X394400Y-230933D01*
X395000Y-231467D01*
X395700Y-231600D01*
X396400Y-231333D01*
X397100Y-230534D01*
G01X402000Y-231600D02*
Y-226267D01*
G01Y-227333D02*
X402500Y-226800D01*
X403000Y-226400D01*
X403700Y-226267D01*
X404200Y-226400D01*
X404800Y-226800D01*
G01X409900Y-228000D02*
X413100D01*
X412800Y-227067D01*
X412300Y-226533D01*
X411600Y-226267D01*
X410900Y-226400D01*
X410300Y-226800D01*
X409900Y-227733D01*
X409700Y-228534D01*
Y-229333D01*
X409900Y-230133D01*
X410400Y-230933D01*
X411000Y-231467D01*
X411700Y-231600D01*
X412400Y-231333D01*
X413100Y-230534D01*
G01X418800Y-231600D02*
Y-224800D01*
X419000Y-224133D01*
X419400Y-223733D01*
X420000Y-223600D01*
X420600Y-223867D01*
X420900Y-224533D01*
G01X419700Y-226800D02*
X417700D01*
G01X427400Y-231600D02*
X426800Y-231467D01*
X426200Y-230933D01*
X425800Y-230000D01*
X425600Y-228933D01*
X425800Y-227867D01*
X426200Y-226933D01*
X426800Y-226400D01*
X427400Y-226267D01*
X428000Y-226400D01*
X428600Y-226933D01*
X429000Y-227867D01*
X429100Y-228933D01*
X429000Y-230000D01*
X428600Y-230933D01*
X428000Y-231467D01*
X427400Y-231600D01*
G01X434000D02*
Y-226267D01*
G01Y-227333D02*
X434500Y-226800D01*
X435000Y-226400D01*
X435700Y-226267D01*
X436200Y-226400D01*
X436800Y-226800D01*
G01X441900Y-228000D02*
X445100D01*
X444800Y-227067D01*
X444300Y-226533D01*
X443600Y-226267D01*
X442900Y-226400D01*
X442300Y-226800D01*
X441900Y-227733D01*
X441700Y-228534D01*
Y-229333D01*
X441900Y-230133D01*
X442400Y-230933D01*
X443000Y-231467D01*
X443700Y-231600D01*
X444400Y-231333D01*
X445100Y-230534D01*
G01X451200Y-233067D02*
X451600Y-231333D01*
G01X465600Y-234267D02*
Y-226267D01*
G01Y-227467D02*
X466100Y-226800D01*
X466600Y-226400D01*
X467400Y-226267D01*
X468100Y-226400D01*
X468800Y-227067D01*
X469100Y-228000D01*
X469200Y-228933D01*
X469100Y-229867D01*
X468800Y-230800D01*
X468200Y-231333D01*
X467400Y-231600D01*
X466700Y-231467D01*
X466000Y-231067D01*
X465600Y-230534D01*
G01X475400Y-231600D02*
Y-223600D01*
G01X481900Y-228000D02*
X485100D01*
X484800Y-227067D01*
X484300Y-226533D01*
X483600Y-226267D01*
X482900Y-226400D01*
X482300Y-226800D01*
X481900Y-227733D01*
X481700Y-228534D01*
Y-229333D01*
X481900Y-230133D01*
X482400Y-230933D01*
X483000Y-231467D01*
X483700Y-231600D01*
X484400Y-231333D01*
X485100Y-230534D01*
G01X493200Y-231600D02*
Y-226267D01*
G01Y-227200D02*
X492800Y-226667D01*
X492200Y-226400D01*
X491500Y-226267D01*
X490800Y-226533D01*
X490200Y-227067D01*
X489800Y-227867D01*
X489600Y-228933D01*
X489800Y-230000D01*
X490200Y-230800D01*
X490800Y-231333D01*
X491500Y-231600D01*
X492200Y-231467D01*
X492800Y-231067D01*
X493200Y-230534D01*
G01X497900Y-230667D02*
X498400Y-231200D01*
X499100Y-231600D01*
X499700D01*
X500300Y-231333D01*
X500700Y-230933D01*
X500900Y-230400D01*
X500800Y-229600D01*
X500400Y-229200D01*
X498600Y-228400D01*
X498200Y-227467D01*
X498400Y-226800D01*
X498800Y-226400D01*
X499400Y-226267D01*
X500000Y-226400D01*
X500600Y-226800D01*
G01X505900Y-228000D02*
X509100D01*
X508800Y-227067D01*
X508300Y-226533D01*
X507600Y-226267D01*
X506900Y-226400D01*
X506300Y-226800D01*
X505900Y-227733D01*
X505700Y-228534D01*
Y-229333D01*
X505900Y-230133D01*
X506400Y-230933D01*
X507000Y-231467D01*
X507700Y-231600D01*
X508400Y-231333D01*
X509100Y-230534D01*
G01X522800Y-231600D02*
Y-224800D01*
X523000Y-224133D01*
X523400Y-223733D01*
X524000Y-223600D01*
X524600Y-223867D01*
X524900Y-224533D01*
G01X523700Y-226800D02*
X521700D01*
G01X531400Y-231600D02*
X530800Y-231467D01*
X530200Y-230933D01*
X529800Y-230000D01*
X529600Y-228933D01*
X529800Y-227867D01*
X530200Y-226933D01*
X530800Y-226400D01*
X531400Y-226267D01*
X532000Y-226400D01*
X532600Y-226933D01*
X533000Y-227867D01*
X533100Y-228933D01*
X533000Y-230000D01*
X532600Y-230933D01*
X532000Y-231467D01*
X531400Y-231600D01*
G01X539400D02*
Y-223600D01*
G01X547400Y-231600D02*
Y-223600D01*
G01X555400Y-231600D02*
X554800Y-231467D01*
X554200Y-230933D01*
X553800Y-230000D01*
X553600Y-228933D01*
X553800Y-227867D01*
X554200Y-226933D01*
X554800Y-226400D01*
X555400Y-226267D01*
X556000Y-226400D01*
X556600Y-226933D01*
X557000Y-227867D01*
X557100Y-228933D01*
X557000Y-230000D01*
X556600Y-230933D01*
X556000Y-231467D01*
X555400Y-231600D01*
G01X560900Y-226267D02*
X562100Y-231600D01*
X563400Y-226267D01*
X564700Y-231600D01*
X565900Y-226267D01*
G01X577200Y-230000D02*
X577800Y-230933D01*
X578600Y-231467D01*
X579500Y-231600D01*
X580300Y-231467D01*
X581100Y-230800D01*
X581600Y-230000D01*
X581700Y-229200D01*
X581500Y-228267D01*
X580800Y-227600D01*
X580100Y-227333D01*
X579200D01*
G01X580100D02*
X580700Y-226933D01*
X581200Y-226267D01*
X581400Y-225467D01*
X581200Y-224667D01*
X580700Y-224000D01*
X579800Y-223600D01*
X578900Y-223733D01*
X578000Y-224267D01*
G01X587400Y-231867D02*
X587200Y-231733D01*
Y-231467D01*
X587400Y-231333D01*
X587600Y-231467D01*
Y-231733D01*
X587400Y-231867D01*
G01X595400Y-231600D02*
Y-223600D01*
X594200Y-225200D01*
G01Y-231600D02*
X596600D01*
G01X603400D02*
X604100Y-231467D01*
X604900Y-231067D01*
X605400Y-230400D01*
X605600Y-229467D01*
X605400Y-228534D01*
X604800Y-227733D01*
X603900Y-227333D01*
X602900D01*
X602300Y-227067D01*
X601800Y-226400D01*
X601600Y-225467D01*
X601900Y-224533D01*
X602600Y-223867D01*
X603400Y-223600D01*
X604200Y-223867D01*
X604900Y-224533D01*
X605200Y-225467D01*
X605000Y-226400D01*
X604500Y-227067D01*
X603900Y-227333D01*
X602900D01*
X602000Y-227733D01*
X601400Y-228534D01*
X601200Y-229467D01*
X601400Y-230400D01*
X601900Y-231067D01*
X602700Y-231467D01*
X603400Y-231600D01*
G01X608400D02*
Y-226267D01*
G01Y-227733D02*
X608700Y-227067D01*
X609200Y-226533D01*
X609900Y-226267D01*
X610600Y-226533D01*
X611100Y-227067D01*
X611400Y-227733D01*
Y-231600D01*
G01Y-227733D02*
X611700Y-227067D01*
X612200Y-226533D01*
X612900Y-226267D01*
X613600Y-226533D01*
X614100Y-227067D01*
X614400Y-227867D01*
Y-231600D01*
G01X616400D02*
Y-226267D01*
G01Y-227733D02*
X616700Y-227067D01*
X617200Y-226533D01*
X617900Y-226267D01*
X618600Y-226533D01*
X619100Y-227067D01*
X619400Y-227733D01*
Y-231600D01*
G01Y-227733D02*
X619700Y-227067D01*
X620200Y-226533D01*
X620900Y-226267D01*
X621600Y-226533D01*
X622100Y-227067D01*
X622400Y-227867D01*
Y-231600D01*
G01X635400Y-223600D02*
Y-231600D01*
G01X634000Y-226267D02*
X636800D01*
G01X643400Y-231600D02*
X642800Y-231467D01*
X642200Y-230933D01*
X641800Y-230000D01*
X641600Y-228933D01*
X641800Y-227867D01*
X642200Y-226933D01*
X642800Y-226400D01*
X643400Y-226267D01*
X644000Y-226400D01*
X644600Y-226933D01*
X645000Y-227867D01*
X645100Y-228933D01*
X645000Y-230000D01*
X644600Y-230933D01*
X644000Y-231467D01*
X643400Y-231600D01*
G01X657600Y-234267D02*
Y-226267D01*
G01Y-227467D02*
X658100Y-226800D01*
X658600Y-226400D01*
X659400Y-226267D01*
X660100Y-226400D01*
X660800Y-227067D01*
X661100Y-228000D01*
X661200Y-228933D01*
X661100Y-229867D01*
X660800Y-230800D01*
X660200Y-231333D01*
X659400Y-231600D01*
X658700Y-231467D01*
X658000Y-231067D01*
X657600Y-230534D01*
G01X666000Y-231600D02*
Y-226267D01*
G01Y-227333D02*
X666500Y-226800D01*
X667000Y-226400D01*
X667700Y-226267D01*
X668200Y-226400D01*
X668800Y-226800D01*
G01X675400Y-231600D02*
X674800Y-231467D01*
X674200Y-230933D01*
X673800Y-230000D01*
X673600Y-228933D01*
X673800Y-227867D01*
X674200Y-226933D01*
X674800Y-226400D01*
X675400Y-226267D01*
X676000Y-226400D01*
X676600Y-226933D01*
X677000Y-227867D01*
X677100Y-228933D01*
X677000Y-230000D01*
X676600Y-230933D01*
X676000Y-231467D01*
X675400Y-231600D01*
G01X685200Y-223600D02*
Y-231600D01*
G01Y-230400D02*
X684800Y-231067D01*
X684200Y-231467D01*
X683500Y-231600D01*
X682700Y-231333D01*
X682100Y-230667D01*
X681700Y-229867D01*
X681600Y-228933D01*
X681700Y-228000D01*
X682100Y-227200D01*
X682700Y-226533D01*
X683500Y-226267D01*
X684200Y-226400D01*
X684700Y-226667D01*
X685200Y-227200D01*
G01X689700Y-226267D02*
Y-230000D01*
X690100Y-230933D01*
X690700Y-231467D01*
X691400Y-231600D01*
X692100Y-231467D01*
X692700Y-230933D01*
X693100Y-230000D01*
G01Y-231600D02*
Y-226267D01*
G01X701000Y-226933D02*
X700300Y-226400D01*
X699700Y-226267D01*
X698900Y-226533D01*
X698300Y-227067D01*
X697900Y-228000D01*
X697800Y-228933D01*
X697900Y-229867D01*
X698300Y-230667D01*
X698900Y-231333D01*
X699700Y-231600D01*
X700400Y-231333D01*
X701000Y-230800D01*
G01X705900Y-228000D02*
X709100D01*
X708800Y-227067D01*
X708300Y-226533D01*
X707600Y-226267D01*
X706900Y-226400D01*
X706300Y-226800D01*
X705900Y-227733D01*
X705700Y-228534D01*
Y-229333D01*
X705900Y-230133D01*
X706400Y-230933D01*
X707000Y-231467D01*
X707700Y-231600D01*
X708400Y-231333D01*
X709100Y-230534D01*
G01X723400Y-223600D02*
Y-231600D01*
G01X722000Y-226267D02*
X724800D01*
G01X729700Y-231600D02*
Y-223600D01*
G01Y-227467D02*
X730200Y-226800D01*
X730700Y-226400D01*
X731500Y-226267D01*
X732100Y-226400D01*
X732800Y-226933D01*
X733100Y-227733D01*
Y-231600D01*
G01X739400Y-226267D02*
Y-231600D01*
G01Y-224133D02*
X739200Y-224000D01*
Y-223733D01*
X739400Y-223600D01*
X739600Y-223733D01*
Y-224000D01*
X739400Y-224133D01*
G01X745900Y-230667D02*
X746400Y-231200D01*
X747100Y-231600D01*
X747700D01*
X748300Y-231333D01*
X748700Y-230933D01*
X748900Y-230400D01*
X748800Y-229600D01*
X748400Y-229200D01*
X746600Y-228400D01*
X746200Y-227467D01*
X746400Y-226800D01*
X746800Y-226400D01*
X747400Y-226267D01*
X748000Y-226400D01*
X748600Y-226800D01*
G01X761600Y-231600D02*
Y-223600D01*
G01Y-227600D02*
X762100Y-226800D01*
X762700Y-226400D01*
X763300Y-226267D01*
X764200Y-226533D01*
X764800Y-227067D01*
X765200Y-228000D01*
Y-229067D01*
X765000Y-230133D01*
X764600Y-230933D01*
X763900Y-231467D01*
X763300Y-231600D01*
X762700Y-231467D01*
X762100Y-231067D01*
X761600Y-230400D01*
G01X771400Y-231600D02*
X770800Y-231467D01*
X770200Y-230933D01*
X769800Y-230000D01*
X769600Y-228933D01*
X769800Y-227867D01*
X770200Y-226933D01*
X770800Y-226400D01*
X771400Y-226267D01*
X772000Y-226400D01*
X772600Y-226933D01*
X773000Y-227867D01*
X773100Y-228933D01*
X773000Y-230000D01*
X772600Y-230933D01*
X772000Y-231467D01*
X771400Y-231600D01*
G01X781200D02*
Y-226267D01*
G01Y-227200D02*
X780800Y-226667D01*
X780200Y-226400D01*
X779500Y-226267D01*
X778800Y-226533D01*
X778200Y-227067D01*
X777800Y-227867D01*
X777600Y-228933D01*
X777800Y-230000D01*
X778200Y-230800D01*
X778800Y-231333D01*
X779500Y-231600D01*
X780200Y-231467D01*
X780800Y-231067D01*
X781200Y-230534D01*
G01X786000Y-231600D02*
Y-226267D01*
G01Y-227333D02*
X786500Y-226800D01*
X787000Y-226400D01*
X787700Y-226267D01*
X788200Y-226400D01*
X788800Y-226800D01*
G01X797200Y-223600D02*
Y-231600D01*
G01Y-230400D02*
X796800Y-231067D01*
X796200Y-231467D01*
X795500Y-231600D01*
X794700Y-231333D01*
X794100Y-230667D01*
X793700Y-229867D01*
X793600Y-228933D01*
X793700Y-228000D01*
X794100Y-227200D01*
X794700Y-226533D01*
X795500Y-226267D01*
X796200Y-226400D01*
X796700Y-226667D01*
X797200Y-227200D01*
G01X803400Y-231867D02*
X803200Y-231733D01*
Y-231467D01*
X803400Y-231333D01*
X803600Y-231467D01*
Y-231733D01*
X803400Y-231867D01*
G01X379200Y-213600D02*
Y-221600D01*
G01X376900Y-213600D02*
X381500D01*
G01X385500Y-221600D02*
Y-213600D01*
G01Y-217467D02*
X386000Y-216800D01*
X386500Y-216400D01*
X387300Y-216267D01*
X387900Y-216400D01*
X388600Y-216933D01*
X388900Y-217733D01*
Y-221600D01*
G01X393700Y-218000D02*
X396900D01*
X396600Y-217067D01*
X396100Y-216533D01*
X395400Y-216267D01*
X394700Y-216400D01*
X394100Y-216800D01*
X393700Y-217733D01*
X393500Y-218534D01*
Y-219333D01*
X393700Y-220133D01*
X394200Y-220933D01*
X394800Y-221467D01*
X395500Y-221600D01*
X396200Y-221333D01*
X396900Y-220534D01*
G01X401500Y-221600D02*
Y-216267D01*
G01Y-217600D02*
X401900Y-216933D01*
X402500Y-216400D01*
X403300Y-216267D01*
X404000Y-216400D01*
X404600Y-216933D01*
X404900Y-217867D01*
Y-221600D01*
G01X420800Y-216933D02*
X420100Y-216400D01*
X419500Y-216267D01*
X418700Y-216533D01*
X418100Y-217067D01*
X417700Y-218000D01*
X417600Y-218933D01*
X417700Y-219867D01*
X418100Y-220667D01*
X418700Y-221333D01*
X419500Y-221600D01*
X420200Y-221333D01*
X420800Y-220800D01*
G01X427200Y-221600D02*
X426600Y-221467D01*
X426000Y-220933D01*
X425600Y-220000D01*
X425400Y-218933D01*
X425600Y-217867D01*
X426000Y-216933D01*
X426600Y-216400D01*
X427200Y-216267D01*
X427800Y-216400D01*
X428400Y-216933D01*
X428800Y-217867D01*
X428900Y-218933D01*
X428800Y-220000D01*
X428400Y-220933D01*
X427800Y-221467D01*
X427200Y-221600D01*
G01X433500D02*
Y-216267D01*
G01Y-217600D02*
X433900Y-216933D01*
X434500Y-216400D01*
X435300Y-216267D01*
X436000Y-216400D01*
X436600Y-216933D01*
X436900Y-217867D01*
Y-221600D01*
G01X441400Y-216267D02*
X443200Y-221600D01*
X445000Y-216267D01*
G01X449700Y-218000D02*
X452900D01*
X452600Y-217067D01*
X452100Y-216533D01*
X451400Y-216267D01*
X450700Y-216400D01*
X450100Y-216800D01*
X449700Y-217733D01*
X449500Y-218534D01*
Y-219333D01*
X449700Y-220133D01*
X450200Y-220933D01*
X450800Y-221467D01*
X451500Y-221600D01*
X452200Y-221333D01*
X452900Y-220534D01*
G01X457800Y-221600D02*
Y-216267D01*
G01Y-217333D02*
X458300Y-216800D01*
X458800Y-216400D01*
X459500Y-216267D01*
X460000Y-216400D01*
X460600Y-216800D01*
G01X467200Y-213600D02*
Y-221600D01*
G01X465800Y-216267D02*
X468600D01*
G01X481000Y-220000D02*
X481600Y-220933D01*
X482400Y-221467D01*
X483300Y-221600D01*
X484100Y-221467D01*
X484900Y-220800D01*
X485400Y-220000D01*
X485500Y-219200D01*
X485300Y-218267D01*
X484600Y-217600D01*
X483900Y-217333D01*
X483000D01*
G01X483900D02*
X484500Y-216933D01*
X485000Y-216267D01*
X485200Y-215467D01*
X485000Y-214667D01*
X484500Y-214000D01*
X483600Y-213600D01*
X482700Y-213733D01*
X481800Y-214267D01*
G01X491200Y-221867D02*
X491000Y-221733D01*
Y-221467D01*
X491200Y-221333D01*
X491400Y-221467D01*
Y-221733D01*
X491200Y-221867D01*
G01X499200Y-221600D02*
Y-213600D01*
X498000Y-215200D01*
G01Y-221600D02*
X500400D01*
G01X507200D02*
X507900Y-221467D01*
X508700Y-221067D01*
X509200Y-220400D01*
X509400Y-219467D01*
X509200Y-218534D01*
X508600Y-217733D01*
X507700Y-217333D01*
X506700D01*
X506100Y-217067D01*
X505600Y-216400D01*
X505400Y-215467D01*
X505700Y-214533D01*
X506400Y-213867D01*
X507200Y-213600D01*
X508000Y-213867D01*
X508700Y-214533D01*
X509000Y-215467D01*
X508800Y-216400D01*
X508300Y-217067D01*
X507700Y-217333D01*
X506700D01*
X505800Y-217733D01*
X505200Y-218534D01*
X505000Y-219467D01*
X505200Y-220400D01*
X505700Y-221067D01*
X506500Y-221467D01*
X507200Y-221600D01*
G01X512200D02*
Y-216267D01*
G01Y-217733D02*
X512500Y-217067D01*
X513000Y-216533D01*
X513700Y-216267D01*
X514400Y-216533D01*
X514900Y-217067D01*
X515200Y-217733D01*
Y-221600D01*
G01Y-217733D02*
X515500Y-217067D01*
X516000Y-216533D01*
X516700Y-216267D01*
X517400Y-216533D01*
X517900Y-217067D01*
X518200Y-217867D01*
Y-221600D01*
G01X520200D02*
Y-216267D01*
G01Y-217733D02*
X520500Y-217067D01*
X521000Y-216533D01*
X521700Y-216267D01*
X522400Y-216533D01*
X522900Y-217067D01*
X523200Y-217733D01*
Y-221600D01*
G01Y-217733D02*
X523500Y-217067D01*
X524000Y-216533D01*
X524700Y-216267D01*
X525400Y-216533D01*
X525900Y-217067D01*
X526200Y-217867D01*
Y-221600D01*
G01X539200Y-216267D02*
Y-221600D01*
G01Y-214133D02*
X539000Y-214000D01*
Y-213733D01*
X539200Y-213600D01*
X539400Y-213733D01*
Y-214000D01*
X539200Y-214133D01*
G01X545500Y-221600D02*
Y-216267D01*
G01Y-217600D02*
X545900Y-216933D01*
X546500Y-216400D01*
X547300Y-216267D01*
X548000Y-216400D01*
X548600Y-216933D01*
X548900Y-217867D01*
Y-221600D01*
G01X555200Y-213600D02*
Y-221600D01*
G01X553800Y-216267D02*
X556600D01*
G01X563200Y-221600D02*
X562600Y-221467D01*
X562000Y-220933D01*
X561600Y-220000D01*
X561400Y-218933D01*
X561600Y-217867D01*
X562000Y-216933D01*
X562600Y-216400D01*
X563200Y-216267D01*
X563800Y-216400D01*
X564400Y-216933D01*
X564800Y-217867D01*
X564900Y-218933D01*
X564800Y-220000D01*
X564400Y-220933D01*
X563800Y-221467D01*
X563200Y-221600D01*
G01X579200D02*
Y-213600D01*
X578000Y-215200D01*
G01Y-221600D02*
X580400D01*
G01X585300Y-214933D02*
X585900Y-214133D01*
X586600Y-213733D01*
X587400Y-213600D01*
X588400Y-213867D01*
X589100Y-214533D01*
X589300Y-215333D01*
X589200Y-216134D01*
X588800Y-216800D01*
X586800Y-218133D01*
X585900Y-219067D01*
X585300Y-220400D01*
X585100Y-221600D01*
X589300D01*
G01X593000Y-220400D02*
X593600Y-221067D01*
X594300Y-221467D01*
X595200Y-221600D01*
X596100Y-221333D01*
X596800Y-220800D01*
X597300Y-219867D01*
X597400Y-218800D01*
X597200Y-217733D01*
X596700Y-217067D01*
X596000Y-216533D01*
X595300Y-216400D01*
X594600Y-216533D01*
X593700Y-217067D01*
X594000Y-213600D01*
X596700D01*
G01X603200Y-221867D02*
X603000Y-221733D01*
Y-221467D01*
X603200Y-221333D01*
X603400Y-221467D01*
Y-221733D01*
X603200Y-221867D01*
G01X611200Y-221600D02*
Y-213600D01*
X610000Y-215200D01*
G01Y-221600D02*
X612400D01*
G01X617500Y-220667D02*
X618200Y-221333D01*
X619000Y-221600D01*
X619800Y-221333D01*
X620500Y-220534D01*
X621000Y-219333D01*
X621200Y-218133D01*
Y-216667D01*
X621000Y-215467D01*
X620500Y-214400D01*
X619900Y-213867D01*
X619200Y-213600D01*
X618400Y-213867D01*
X617800Y-214400D01*
X617400Y-215200D01*
X617200Y-216267D01*
X617400Y-217200D01*
X617900Y-218133D01*
X618500Y-218667D01*
X619200Y-218800D01*
X620000Y-218534D01*
X620600Y-217867D01*
X621200Y-216667D01*
G01X625300Y-218267D02*
X626000Y-217333D01*
X626600Y-216800D01*
X627400Y-216533D01*
X628100Y-216800D01*
X628600Y-217333D01*
X629000Y-218133D01*
X629100Y-219067D01*
X629000Y-219867D01*
X628600Y-220667D01*
X628000Y-221333D01*
X627300Y-221600D01*
X626500Y-221333D01*
X625800Y-220534D01*
X625400Y-219333D01*
X625300Y-218000D01*
X625500Y-216267D01*
X625800Y-215333D01*
X626300Y-214400D01*
X627000Y-213733D01*
X627700Y-213600D01*
X628400Y-213867D01*
X628900Y-214533D01*
G01X635200Y-221600D02*
X635900Y-221467D01*
X636700Y-221067D01*
X637200Y-220400D01*
X637400Y-219467D01*
X637200Y-218534D01*
X636600Y-217733D01*
X635700Y-217333D01*
X634700D01*
X634100Y-217067D01*
X633600Y-216400D01*
X633400Y-215467D01*
X633700Y-214533D01*
X634400Y-213867D01*
X635200Y-213600D01*
X636000Y-213867D01*
X636700Y-214533D01*
X637000Y-215467D01*
X636800Y-216400D01*
X636300Y-217067D01*
X635700Y-217333D01*
X634700D01*
X633800Y-217733D01*
X633200Y-218534D01*
X633000Y-219467D01*
X633200Y-220400D01*
X633700Y-221067D01*
X634500Y-221467D01*
X635200Y-221600D01*
G01X640200D02*
Y-216267D01*
G01Y-217733D02*
X640500Y-217067D01*
X641000Y-216533D01*
X641700Y-216267D01*
X642400Y-216533D01*
X642900Y-217067D01*
X643200Y-217733D01*
Y-221600D01*
G01Y-217733D02*
X643500Y-217067D01*
X644000Y-216533D01*
X644700Y-216267D01*
X645400Y-216533D01*
X645900Y-217067D01*
X646200Y-217867D01*
Y-221600D01*
G01X651200Y-216267D02*
Y-221600D01*
G01Y-214133D02*
X651000Y-214000D01*
Y-213733D01*
X651200Y-213600D01*
X651400Y-213733D01*
Y-214000D01*
X651200Y-214133D01*
G01X659200Y-221600D02*
Y-213600D01*
G01X667000Y-223067D02*
X667400Y-221333D01*
G01X683200Y-213600D02*
Y-221600D01*
G01X681800Y-216267D02*
X684600D01*
G01X689500Y-221600D02*
Y-213600D01*
G01Y-217467D02*
X690000Y-216800D01*
X690500Y-216400D01*
X691300Y-216267D01*
X691900Y-216400D01*
X692600Y-216933D01*
X692900Y-217733D01*
Y-221600D01*
G01X697700Y-218000D02*
X700900D01*
X700600Y-217067D01*
X700100Y-216533D01*
X699400Y-216267D01*
X698700Y-216400D01*
X698100Y-216800D01*
X697700Y-217733D01*
X697500Y-218534D01*
Y-219333D01*
X697700Y-220133D01*
X698200Y-220933D01*
X698800Y-221467D01*
X699500Y-221600D01*
X700200Y-221333D01*
X700900Y-220534D01*
G01X717000Y-213600D02*
Y-221600D01*
G01Y-220400D02*
X716600Y-221067D01*
X716000Y-221467D01*
X715300Y-221600D01*
X714500Y-221333D01*
X713900Y-220667D01*
X713500Y-219867D01*
X713400Y-218933D01*
X713500Y-218000D01*
X713900Y-217200D01*
X714500Y-216533D01*
X715300Y-216267D01*
X716000Y-216400D01*
X716500Y-216667D01*
X717000Y-217200D01*
G01X723200Y-216267D02*
Y-221600D01*
G01Y-214133D02*
X723000Y-214000D01*
Y-213733D01*
X723200Y-213600D01*
X723400Y-213733D01*
Y-214000D01*
X723200Y-214133D01*
G01X730600Y-221600D02*
Y-214800D01*
X730800Y-214133D01*
X731200Y-213733D01*
X731800Y-213600D01*
X732400Y-213867D01*
X732700Y-214533D01*
G01X731500Y-216800D02*
X729500D01*
G01X738600Y-221600D02*
Y-214800D01*
X738800Y-214133D01*
X739200Y-213733D01*
X739800Y-213600D01*
X740400Y-213867D01*
X740700Y-214533D01*
G01X739500Y-216800D02*
X737500D01*
G01X745700Y-218000D02*
X748900D01*
X748600Y-217067D01*
X748100Y-216533D01*
X747400Y-216267D01*
X746700Y-216400D01*
X746100Y-216800D01*
X745700Y-217733D01*
X745500Y-218534D01*
Y-219333D01*
X745700Y-220133D01*
X746200Y-220933D01*
X746800Y-221467D01*
X747500Y-221600D01*
X748200Y-221333D01*
X748900Y-220534D01*
G01X753800Y-221600D02*
Y-216267D01*
G01Y-217333D02*
X754300Y-216800D01*
X754800Y-216400D01*
X755500Y-216267D01*
X756000Y-216400D01*
X756600Y-216800D01*
G01X761700Y-218000D02*
X764900D01*
X764600Y-217067D01*
X764100Y-216533D01*
X763400Y-216267D01*
X762700Y-216400D01*
X762100Y-216800D01*
X761700Y-217733D01*
X761500Y-218534D01*
Y-219333D01*
X761700Y-220133D01*
X762200Y-220933D01*
X762800Y-221467D01*
X763500Y-221600D01*
X764200Y-221333D01*
X764900Y-220534D01*
G01X769500Y-221600D02*
Y-216267D01*
G01Y-217600D02*
X769900Y-216933D01*
X770500Y-216400D01*
X771300Y-216267D01*
X772000Y-216400D01*
X772600Y-216933D01*
X772900Y-217867D01*
Y-221600D01*
G01X780800Y-216933D02*
X780100Y-216400D01*
X779500Y-216267D01*
X778700Y-216533D01*
X778100Y-217067D01*
X777700Y-218000D01*
X777600Y-218933D01*
X777700Y-219867D01*
X778100Y-220667D01*
X778700Y-221333D01*
X779500Y-221600D01*
X780200Y-221333D01*
X780800Y-220800D01*
G01X785700Y-218000D02*
X788900D01*
X788600Y-217067D01*
X788100Y-216533D01*
X787400Y-216267D01*
X786700Y-216400D01*
X786100Y-216800D01*
X785700Y-217733D01*
X785500Y-218534D01*
Y-219333D01*
X785700Y-220133D01*
X786200Y-220933D01*
X786800Y-221467D01*
X787500Y-221600D01*
X788200Y-221333D01*
X788900Y-220534D01*
G01X801400Y-221600D02*
Y-213600D01*
G01Y-217600D02*
X801900Y-216800D01*
X802500Y-216400D01*
X803100Y-216267D01*
X804000Y-216533D01*
X804600Y-217067D01*
X805000Y-218000D01*
Y-219067D01*
X804800Y-220133D01*
X804400Y-220933D01*
X803700Y-221467D01*
X803100Y-221600D01*
X802500Y-221467D01*
X801900Y-221067D01*
X801400Y-220400D01*
G01X809700Y-218000D02*
X812900D01*
X812600Y-217067D01*
X812100Y-216533D01*
X811400Y-216267D01*
X810700Y-216400D01*
X810100Y-216800D01*
X809700Y-217733D01*
X809500Y-218534D01*
Y-219333D01*
X809700Y-220133D01*
X810200Y-220933D01*
X810800Y-221467D01*
X811500Y-221600D01*
X812200Y-221333D01*
X812900Y-220534D01*
G01X819200Y-213600D02*
Y-221600D01*
G01X817800Y-216267D02*
X820600D01*
G01X824700D02*
X825900Y-221600D01*
X827200Y-216267D01*
X828500Y-221600D01*
X829700Y-216267D01*
G01X833700Y-218000D02*
X836900D01*
X836600Y-217067D01*
X836100Y-216533D01*
X835400Y-216267D01*
X834700Y-216400D01*
X834100Y-216800D01*
X833700Y-217733D01*
X833500Y-218534D01*
Y-219333D01*
X833700Y-220133D01*
X834200Y-220933D01*
X834800Y-221467D01*
X835500Y-221600D01*
X836200Y-221333D01*
X836900Y-220534D01*
G01X841700Y-218000D02*
X844900D01*
X844600Y-217067D01*
X844100Y-216533D01*
X843400Y-216267D01*
X842700Y-216400D01*
X842100Y-216800D01*
X841700Y-217733D01*
X841500Y-218534D01*
Y-219333D01*
X841700Y-220133D01*
X842200Y-220933D01*
X842800Y-221467D01*
X843500Y-221600D01*
X844200Y-221333D01*
X844900Y-220534D01*
G01X849500Y-221600D02*
Y-216267D01*
G01Y-217600D02*
X849900Y-216933D01*
X850500Y-216400D01*
X851300Y-216267D01*
X852000Y-216400D01*
X852600Y-216933D01*
X852900Y-217867D01*
Y-221600D01*
G01X867200D02*
Y-213600D01*
X866000Y-215200D01*
G01Y-221600D02*
X868400D01*
G01X873300Y-214933D02*
X873900Y-214133D01*
X874600Y-213733D01*
X875400Y-213600D01*
X876400Y-213867D01*
X877100Y-214533D01*
X877300Y-215333D01*
X877200Y-216134D01*
X876800Y-216800D01*
X874800Y-218133D01*
X873900Y-219067D01*
X873300Y-220400D01*
X873100Y-221600D01*
X877300D01*
G01X881300Y-218267D02*
X882000Y-217333D01*
X882600Y-216800D01*
X883400Y-216533D01*
X884100Y-216800D01*
X884600Y-217333D01*
X885000Y-218133D01*
X885100Y-219067D01*
X885000Y-219867D01*
X884600Y-220667D01*
X884000Y-221333D01*
X883300Y-221600D01*
X882500Y-221333D01*
X881800Y-220534D01*
X881400Y-219333D01*
X881300Y-218000D01*
X881500Y-216267D01*
X881800Y-215333D01*
X882300Y-214400D01*
X883000Y-213733D01*
X883700Y-213600D01*
X884400Y-213867D01*
X884900Y-214533D01*
G01X888200Y-221600D02*
Y-216267D01*
G01Y-217733D02*
X888500Y-217067D01*
X889000Y-216533D01*
X889700Y-216267D01*
X890400Y-216533D01*
X890900Y-217067D01*
X891200Y-217733D01*
Y-221600D01*
G01Y-217733D02*
X891500Y-217067D01*
X892000Y-216533D01*
X892700Y-216267D01*
X893400Y-216533D01*
X893900Y-217067D01*
X894200Y-217867D01*
Y-221600D01*
G01X899200Y-216267D02*
Y-221600D01*
G01Y-214133D02*
X899000Y-214000D01*
Y-213733D01*
X899200Y-213600D01*
X899400Y-213733D01*
Y-214000D01*
X899200Y-214133D01*
G01X907200Y-221600D02*
Y-213600D01*
G01X925000Y-221600D02*
Y-216267D01*
G01Y-217200D02*
X924600Y-216667D01*
X924000Y-216400D01*
X923300Y-216267D01*
X922600Y-216533D01*
X922000Y-217067D01*
X921600Y-217867D01*
X921400Y-218933D01*
X921600Y-220000D01*
X922000Y-220800D01*
X922600Y-221333D01*
X923300Y-221600D01*
X924000Y-221467D01*
X924600Y-221067D01*
X925000Y-220534D01*
G01X929500Y-221600D02*
Y-216267D01*
G01Y-217600D02*
X929900Y-216933D01*
X930500Y-216400D01*
X931300Y-216267D01*
X932000Y-216400D01*
X932600Y-216933D01*
X932900Y-217867D01*
Y-221600D01*
G01X941000Y-213600D02*
Y-221600D01*
G01Y-220400D02*
X940600Y-221067D01*
X940000Y-221467D01*
X939300Y-221600D01*
X938500Y-221333D01*
X937900Y-220667D01*
X937500Y-219867D01*
X937400Y-218933D01*
X937500Y-218000D01*
X937900Y-217200D01*
X938500Y-216533D01*
X939300Y-216267D01*
X940000Y-216400D01*
X940500Y-216667D01*
X941000Y-217200D01*
G01X955200Y-221600D02*
Y-213600D01*
X954000Y-215200D01*
G01Y-221600D02*
X956400D01*
G01X961300Y-214933D02*
X961900Y-214133D01*
X962600Y-213733D01*
X963400Y-213600D01*
X964400Y-213867D01*
X965100Y-214533D01*
X965300Y-215333D01*
X965200Y-216134D01*
X964800Y-216800D01*
X962800Y-218133D01*
X961900Y-219067D01*
X961300Y-220400D01*
X961100Y-221600D01*
X965300D01*
G01X969000Y-220400D02*
X969600Y-221067D01*
X970300Y-221467D01*
X971200Y-221600D01*
X972100Y-221333D01*
X972800Y-220800D01*
X973300Y-219867D01*
X973400Y-218800D01*
X973200Y-217733D01*
X972700Y-217067D01*
X972000Y-216533D01*
X971300Y-216400D01*
X970600Y-216533D01*
X969700Y-217067D01*
X970000Y-213600D01*
X972700D01*
G01X979200Y-221867D02*
X979000Y-221733D01*
Y-221467D01*
X979200Y-221333D01*
X979400Y-221467D01*
Y-221733D01*
X979200Y-221867D01*
G01X987200Y-221600D02*
Y-213600D01*
X986000Y-215200D01*
G01Y-221600D02*
X988400D01*
G01X993500Y-220667D02*
X994200Y-221333D01*
X995000Y-221600D01*
X995800Y-221333D01*
X996500Y-220534D01*
X997000Y-219333D01*
X997200Y-218133D01*
Y-216667D01*
X997000Y-215467D01*
X996500Y-214400D01*
X995900Y-213867D01*
X995200Y-213600D01*
X994400Y-213867D01*
X993800Y-214400D01*
X993400Y-215200D01*
X993200Y-216267D01*
X993400Y-217200D01*
X993900Y-218133D01*
X994500Y-218667D01*
X995200Y-218800D01*
X996000Y-218534D01*
X996600Y-217867D01*
X997200Y-216667D01*
G01X1001300Y-218267D02*
X1002000Y-217333D01*
X1002600Y-216800D01*
X1003400Y-216533D01*
X1004100Y-216800D01*
X1004600Y-217333D01*
X1005000Y-218133D01*
X1005100Y-219067D01*
X1005000Y-219867D01*
X1004600Y-220667D01*
X1004000Y-221333D01*
X1003300Y-221600D01*
X1002500Y-221333D01*
X1001800Y-220534D01*
X1001400Y-219333D01*
X1001300Y-218000D01*
X1001500Y-216267D01*
X1001800Y-215333D01*
X1002300Y-214400D01*
X1003000Y-213733D01*
X1003700Y-213600D01*
X1004400Y-213867D01*
X1004900Y-214533D01*
G01X1011200Y-221600D02*
X1011900Y-221467D01*
X1012700Y-221067D01*
X1013200Y-220400D01*
X1013400Y-219467D01*
X1013200Y-218534D01*
X1012600Y-217733D01*
X1011700Y-217333D01*
X1010700D01*
X1010100Y-217067D01*
X1009600Y-216400D01*
X1009400Y-215467D01*
X1009700Y-214533D01*
X1010400Y-213867D01*
X1011200Y-213600D01*
X1012000Y-213867D01*
X1012700Y-214533D01*
X1013000Y-215467D01*
X1012800Y-216400D01*
X1012300Y-217067D01*
X1011700Y-217333D01*
X1010700D01*
X1009800Y-217733D01*
X1009200Y-218534D01*
X1009000Y-219467D01*
X1009200Y-220400D01*
X1009700Y-221067D01*
X1010500Y-221467D01*
X1011200Y-221600D01*
G01X1027200Y-216267D02*
Y-221600D01*
G01Y-214133D02*
X1027000Y-214000D01*
Y-213733D01*
X1027200Y-213600D01*
X1027400Y-213733D01*
Y-214000D01*
X1027200Y-214133D01*
G01X1033700Y-220667D02*
X1034200Y-221200D01*
X1034900Y-221600D01*
X1035500D01*
X1036100Y-221333D01*
X1036500Y-220933D01*
X1036700Y-220400D01*
X1036600Y-219600D01*
X1036200Y-219200D01*
X1034400Y-218400D01*
X1034000Y-217467D01*
X1034200Y-216800D01*
X1034600Y-216400D01*
X1035200Y-216267D01*
X1035800Y-216400D01*
X1036400Y-216800D01*
G01X1051200Y-221600D02*
Y-213600D01*
G01X1057700Y-218000D02*
X1060900D01*
X1060600Y-217067D01*
X1060100Y-216533D01*
X1059400Y-216267D01*
X1058700Y-216400D01*
X1058100Y-216800D01*
X1057700Y-217733D01*
X1057500Y-218534D01*
Y-219333D01*
X1057700Y-220133D01*
X1058200Y-220933D01*
X1058800Y-221467D01*
X1059500Y-221600D01*
X1060200Y-221333D01*
X1060900Y-220534D01*
G01X1065700Y-220667D02*
X1066200Y-221200D01*
X1066900Y-221600D01*
X1067500D01*
X1068100Y-221333D01*
X1068500Y-220933D01*
X1068700Y-220400D01*
X1068600Y-219600D01*
X1068200Y-219200D01*
X1066400Y-218400D01*
X1066000Y-217467D01*
X1066200Y-216800D01*
X1066600Y-216400D01*
X1067200Y-216267D01*
X1067800Y-216400D01*
X1068400Y-216800D01*
G01X1073700Y-220667D02*
X1074200Y-221200D01*
X1074900Y-221600D01*
X1075500D01*
X1076100Y-221333D01*
X1076500Y-220933D01*
X1076700Y-220400D01*
X1076600Y-219600D01*
X1076200Y-219200D01*
X1074400Y-218400D01*
X1074000Y-217467D01*
X1074200Y-216800D01*
X1074600Y-216400D01*
X1075200Y-216267D01*
X1075800Y-216400D01*
X1076400Y-216800D01*
G01X1091200Y-213600D02*
Y-221600D01*
G01X1089800Y-216267D02*
X1092600D01*
G01X1097500Y-221600D02*
Y-213600D01*
G01Y-217467D02*
X1098000Y-216800D01*
X1098500Y-216400D01*
X1099300Y-216267D01*
X1099900Y-216400D01*
X1100600Y-216933D01*
X1100900Y-217733D01*
Y-221600D01*
G01X1109000D02*
Y-216267D01*
G01Y-217200D02*
X1108600Y-216667D01*
X1108000Y-216400D01*
X1107300Y-216267D01*
X1106600Y-216533D01*
X1106000Y-217067D01*
X1105600Y-217867D01*
X1105400Y-218933D01*
X1105600Y-220000D01*
X1106000Y-220800D01*
X1106600Y-221333D01*
X1107300Y-221600D01*
X1108000Y-221467D01*
X1108600Y-221067D01*
X1109000Y-220534D01*
G01X1113500Y-221600D02*
Y-216267D01*
G01Y-217600D02*
X1113900Y-216933D01*
X1114500Y-216400D01*
X1115300Y-216267D01*
X1116000Y-216400D01*
X1116600Y-216933D01*
X1116900Y-217867D01*
Y-221600D01*
G01X1131200D02*
Y-213600D01*
X1130000Y-215200D01*
G01Y-221600D02*
X1132400D01*
G01X1144200D02*
Y-216267D01*
G01Y-217733D02*
X1144500Y-217067D01*
X1145000Y-216533D01*
X1145700Y-216267D01*
X1146400Y-216533D01*
X1146900Y-217067D01*
X1147200Y-217733D01*
Y-221600D01*
G01Y-217733D02*
X1147500Y-217067D01*
X1148000Y-216533D01*
X1148700Y-216267D01*
X1149400Y-216533D01*
X1149900Y-217067D01*
X1150200Y-217867D01*
Y-221600D01*
G01X1155200Y-216267D02*
Y-221600D01*
G01Y-214133D02*
X1155000Y-214000D01*
Y-213733D01*
X1155200Y-213600D01*
X1155400Y-213733D01*
Y-214000D01*
X1155200Y-214133D01*
G01X1163200Y-221600D02*
Y-213600D01*
G01X1171000Y-223067D02*
X1171400Y-221333D01*
G01X390829Y15500D02*
X393329Y23500D01*
X395829Y15500D01*
G01X394929Y18300D02*
X391729D01*
G01X401329Y15500D02*
Y23500D01*
G01X409329Y20833D02*
Y15500D01*
G01Y22967D02*
X409129Y23100D01*
Y23367D01*
X409329Y23500D01*
X409529Y23367D01*
Y23100D01*
X409329Y22967D01*
G01X415929Y13500D02*
X416629Y12967D01*
X417429Y12833D01*
X418129Y12967D01*
X418729Y13633D01*
X419129Y14567D01*
Y20833D01*
G01Y19767D02*
X418729Y20300D01*
X418129Y20700D01*
X417429Y20833D01*
X416629Y20567D01*
X416129Y20033D01*
X415729Y19100D01*
X415529Y18167D01*
X415629Y17367D01*
X416029Y16433D01*
X416629Y15767D01*
X417429Y15500D01*
X418029Y15633D01*
X418729Y16167D01*
X419129Y16700D01*
G01X423629Y15500D02*
Y20833D01*
G01Y19500D02*
X424029Y20167D01*
X424629Y20700D01*
X425429Y20833D01*
X426129Y20700D01*
X426729Y20167D01*
X427029Y19233D01*
Y15500D01*
G01X430329D02*
Y20833D01*
G01Y19367D02*
X430629Y20033D01*
X431129Y20567D01*
X431829Y20833D01*
X432529Y20567D01*
X433029Y20033D01*
X433329Y19367D01*
Y15500D01*
G01Y19367D02*
X433629Y20033D01*
X434129Y20567D01*
X434829Y20833D01*
X435529Y20567D01*
X436029Y20033D01*
X436329Y19233D01*
Y15500D01*
G01X439829Y19100D02*
X443029D01*
X442729Y20033D01*
X442229Y20567D01*
X441529Y20833D01*
X440829Y20700D01*
X440229Y20300D01*
X439829Y19367D01*
X439629Y18566D01*
Y17767D01*
X439829Y16967D01*
X440329Y16167D01*
X440929Y15633D01*
X441629Y15500D01*
X442329Y15767D01*
X443029Y16566D01*
G01X447629Y15500D02*
Y20833D01*
G01Y19500D02*
X448029Y20167D01*
X448629Y20700D01*
X449429Y20833D01*
X450129Y20700D01*
X450729Y20167D01*
X451029Y19233D01*
Y15500D01*
G01X457329Y23500D02*
Y15500D01*
G01X455929Y20833D02*
X458729D01*
G01X403500Y-52934D02*
X404300Y-53600D01*
X405200Y-54000D01*
X406000D01*
X406800Y-53600D01*
X407400Y-52934D01*
X407700Y-52000D01*
X407500Y-51067D01*
X407000Y-50267D01*
X406100Y-49733D01*
X404900Y-49467D01*
X404200Y-48933D01*
X403900Y-48000D01*
X404100Y-47067D01*
X404600Y-46400D01*
X405300Y-46000D01*
X406000D01*
X406700Y-46267D01*
X407300Y-46933D01*
G01X413600Y-48667D02*
Y-54000D01*
G01Y-46533D02*
X413400Y-46400D01*
Y-46133D01*
X413600Y-46000D01*
X413800Y-46133D01*
Y-46400D01*
X413600Y-46533D01*
G01X420100Y-48667D02*
X423100D01*
X420100Y-54000D01*
X423100D01*
G01X428100Y-50400D02*
X431300D01*
X431000Y-49467D01*
X430500Y-48933D01*
X429800Y-48667D01*
X429100Y-48800D01*
X428500Y-49200D01*
X428100Y-50133D01*
X427900Y-50934D01*
Y-51733D01*
X428100Y-52533D01*
X428600Y-53333D01*
X429200Y-53867D01*
X429900Y-54000D01*
X430600Y-53733D01*
X431300Y-52934D01*
G01X464600Y-13000D02*
Y-21000D01*
X468600D01*
G01X476400D02*
Y-15667D01*
G01Y-16600D02*
X476000Y-16067D01*
X475400Y-15800D01*
X474700Y-15667D01*
X474000Y-15933D01*
X473400Y-16467D01*
X473000Y-17267D01*
X472800Y-18333D01*
X473000Y-19400D01*
X473400Y-20200D01*
X474000Y-20733D01*
X474700Y-21000D01*
X475400Y-20867D01*
X476000Y-20467D01*
X476400Y-19934D01*
G01X481100Y-20067D02*
X481600Y-20600D01*
X482300Y-21000D01*
X482900D01*
X483500Y-20733D01*
X483900Y-20333D01*
X484100Y-19800D01*
X484000Y-19000D01*
X483600Y-18600D01*
X481800Y-17800D01*
X481400Y-16867D01*
X481600Y-16200D01*
X482000Y-15800D01*
X482600Y-15667D01*
X483200Y-15800D01*
X483800Y-16200D01*
G01X489100Y-17400D02*
X492300D01*
X492000Y-16467D01*
X491500Y-15933D01*
X490800Y-15667D01*
X490100Y-15800D01*
X489500Y-16200D01*
X489100Y-17133D01*
X488900Y-17934D01*
Y-18733D01*
X489100Y-19533D01*
X489600Y-20333D01*
X490200Y-20867D01*
X490900Y-21000D01*
X491600Y-20733D01*
X492300Y-19934D01*
G01X497200Y-21000D02*
Y-15667D01*
G01Y-16733D02*
X497700Y-16200D01*
X498200Y-15800D01*
X498900Y-15667D01*
X499400Y-15800D01*
X500000Y-16200D01*
G01X512800Y-15667D02*
X514600Y-21000D01*
X516400Y-15667D01*
G01X522600D02*
Y-21000D01*
G01Y-13533D02*
X522400Y-13400D01*
Y-13133D01*
X522600Y-13000D01*
X522800Y-13133D01*
Y-13400D01*
X522600Y-13533D01*
G01X532400Y-21000D02*
Y-15667D01*
G01Y-16600D02*
X532000Y-16067D01*
X531400Y-15800D01*
X530700Y-15667D01*
X530000Y-15933D01*
X529400Y-16467D01*
X529000Y-17267D01*
X528800Y-18333D01*
X529000Y-19400D01*
X529400Y-20200D01*
X530000Y-20733D01*
X530700Y-21000D01*
X531400Y-20867D01*
X532000Y-20467D01*
X532400Y-19934D01*
G01X544900Y-21000D02*
Y-13000D01*
G01Y-16867D02*
X545400Y-16200D01*
X545900Y-15800D01*
X546700Y-15667D01*
X547300Y-15800D01*
X548000Y-16333D01*
X548300Y-17133D01*
Y-21000D01*
G01X554600D02*
X554000Y-20867D01*
X553400Y-20333D01*
X553000Y-19400D01*
X552800Y-18333D01*
X553000Y-17267D01*
X553400Y-16333D01*
X554000Y-15800D01*
X554600Y-15667D01*
X555200Y-15800D01*
X555800Y-16333D01*
X556200Y-17267D01*
X556300Y-18333D01*
X556200Y-19400D01*
X555800Y-20333D01*
X555200Y-20867D01*
X554600Y-21000D01*
G01X562600D02*
Y-13000D01*
G01X569100Y-17400D02*
X572300D01*
X572000Y-16467D01*
X571500Y-15933D01*
X570800Y-15667D01*
X570100Y-15800D01*
X569500Y-16200D01*
X569100Y-17133D01*
X568900Y-17934D01*
Y-18733D01*
X569100Y-19533D01*
X569600Y-20333D01*
X570200Y-20867D01*
X570900Y-21000D01*
X571600Y-20733D01*
X572300Y-19934D01*
G01X586100Y-23667D02*
X585100Y-22333D01*
X584600Y-21000D01*
Y-15667D01*
X585100Y-14333D01*
X586100Y-13000D01*
G01X592800Y-21000D02*
Y-13000D01*
G01Y-17000D02*
X593300Y-16200D01*
X593900Y-15800D01*
X594500Y-15667D01*
X595400Y-15933D01*
X596000Y-16467D01*
X596400Y-17400D01*
Y-18467D01*
X596200Y-19533D01*
X595800Y-20333D01*
X595100Y-20867D01*
X594500Y-21000D01*
X593900Y-20867D01*
X593300Y-20467D01*
X592800Y-19800D01*
G01X601100Y-17400D02*
X604300D01*
X604000Y-16467D01*
X603500Y-15933D01*
X602800Y-15667D01*
X602100Y-15800D01*
X601500Y-16200D01*
X601100Y-17133D01*
X600900Y-17934D01*
Y-18733D01*
X601100Y-19533D01*
X601600Y-20333D01*
X602200Y-20867D01*
X602900Y-21000D01*
X603600Y-20733D01*
X604300Y-19934D01*
G01X610000Y-21000D02*
Y-14200D01*
X610200Y-13533D01*
X610600Y-13133D01*
X611200Y-13000D01*
X611800Y-13267D01*
X612100Y-13933D01*
G01X610900Y-16200D02*
X608900D01*
G01X618600Y-21000D02*
X618000Y-20867D01*
X617400Y-20333D01*
X617000Y-19400D01*
X616800Y-18333D01*
X617000Y-17267D01*
X617400Y-16333D01*
X618000Y-15800D01*
X618600Y-15667D01*
X619200Y-15800D01*
X619800Y-16333D01*
X620200Y-17267D01*
X620300Y-18333D01*
X620200Y-19400D01*
X619800Y-20333D01*
X619200Y-20867D01*
X618600Y-21000D01*
G01X625200D02*
Y-15667D01*
G01Y-16733D02*
X625700Y-16200D01*
X626200Y-15800D01*
X626900Y-15667D01*
X627400Y-15800D01*
X628000Y-16200D01*
G01X633100Y-17400D02*
X636300D01*
X636000Y-16467D01*
X635500Y-15933D01*
X634800Y-15667D01*
X634100Y-15800D01*
X633500Y-16200D01*
X633100Y-17133D01*
X632900Y-17934D01*
Y-18733D01*
X633100Y-19533D01*
X633600Y-20333D01*
X634200Y-20867D01*
X634900Y-21000D01*
X635600Y-20733D01*
X636300Y-19934D01*
G01X650600Y-13000D02*
Y-21000D01*
G01X649200Y-15667D02*
X652000D01*
G01X656900Y-21000D02*
Y-13000D01*
G01Y-16867D02*
X657400Y-16200D01*
X657900Y-15800D01*
X658700Y-15667D01*
X659300Y-15800D01*
X660000Y-16333D01*
X660300Y-17133D01*
Y-21000D01*
G01X665100Y-17400D02*
X668300D01*
X668000Y-16467D01*
X667500Y-15933D01*
X666800Y-15667D01*
X666100Y-15800D01*
X665500Y-16200D01*
X665100Y-17133D01*
X664900Y-17934D01*
Y-18733D01*
X665100Y-19533D01*
X665600Y-20333D01*
X666200Y-20867D01*
X666900Y-21000D01*
X667600Y-20733D01*
X668300Y-19934D01*
G01X684200Y-16333D02*
X683500Y-15800D01*
X682900Y-15667D01*
X682100Y-15933D01*
X681500Y-16467D01*
X681100Y-17400D01*
X681000Y-18333D01*
X681100Y-19267D01*
X681500Y-20067D01*
X682100Y-20733D01*
X682900Y-21000D01*
X683600Y-20733D01*
X684200Y-20200D01*
G01X690600Y-21000D02*
X690000Y-20867D01*
X689400Y-20333D01*
X689000Y-19400D01*
X688800Y-18333D01*
X689000Y-17267D01*
X689400Y-16333D01*
X690000Y-15800D01*
X690600Y-15667D01*
X691200Y-15800D01*
X691800Y-16333D01*
X692200Y-17267D01*
X692300Y-18333D01*
X692200Y-19400D01*
X691800Y-20333D01*
X691200Y-20867D01*
X690600Y-21000D01*
G01X696800Y-23667D02*
Y-15667D01*
G01Y-16867D02*
X697300Y-16200D01*
X697800Y-15800D01*
X698600Y-15667D01*
X699300Y-15800D01*
X700000Y-16467D01*
X700300Y-17400D01*
X700400Y-18333D01*
X700300Y-19267D01*
X700000Y-20200D01*
X699400Y-20733D01*
X698600Y-21000D01*
X697900Y-20867D01*
X697200Y-20467D01*
X696800Y-19934D01*
G01X704800Y-23667D02*
Y-15667D01*
G01Y-16867D02*
X705300Y-16200D01*
X705800Y-15800D01*
X706600Y-15667D01*
X707300Y-15800D01*
X708000Y-16467D01*
X708300Y-17400D01*
X708400Y-18333D01*
X708300Y-19267D01*
X708000Y-20200D01*
X707400Y-20733D01*
X706600Y-21000D01*
X705900Y-20867D01*
X705200Y-20467D01*
X704800Y-19934D01*
G01X713100Y-17400D02*
X716300D01*
X716000Y-16467D01*
X715500Y-15933D01*
X714800Y-15667D01*
X714100Y-15800D01*
X713500Y-16200D01*
X713100Y-17133D01*
X712900Y-17934D01*
Y-18733D01*
X713100Y-19533D01*
X713600Y-20333D01*
X714200Y-20867D01*
X714900Y-21000D01*
X715600Y-20733D01*
X716300Y-19934D01*
G01X721200Y-21000D02*
Y-15667D01*
G01Y-16733D02*
X721700Y-16200D01*
X722200Y-15800D01*
X722900Y-15667D01*
X723400Y-15800D01*
X724000Y-16200D01*
G01X736800Y-23667D02*
Y-15667D01*
G01Y-16867D02*
X737300Y-16200D01*
X737800Y-15800D01*
X738600Y-15667D01*
X739300Y-15800D01*
X740000Y-16467D01*
X740300Y-17400D01*
X740400Y-18333D01*
X740300Y-19267D01*
X740000Y-20200D01*
X739400Y-20733D01*
X738600Y-21000D01*
X737900Y-20867D01*
X737200Y-20467D01*
X736800Y-19934D01*
G01X746600Y-21000D02*
Y-13000D01*
G01X756400Y-21000D02*
Y-15667D01*
G01Y-16600D02*
X756000Y-16067D01*
X755400Y-15800D01*
X754700Y-15667D01*
X754000Y-15933D01*
X753400Y-16467D01*
X753000Y-17267D01*
X752800Y-18333D01*
X753000Y-19400D01*
X753400Y-20200D01*
X754000Y-20733D01*
X754700Y-21000D01*
X755400Y-20867D01*
X756000Y-20467D01*
X756400Y-19934D01*
G01X762600Y-13000D02*
Y-21000D01*
G01X761200Y-15667D02*
X764000D01*
G01X770600D02*
Y-21000D01*
G01Y-13533D02*
X770400Y-13400D01*
Y-13133D01*
X770600Y-13000D01*
X770800Y-13133D01*
Y-13400D01*
X770600Y-13533D01*
G01X776900Y-21000D02*
Y-15667D01*
G01Y-17000D02*
X777300Y-16333D01*
X777900Y-15800D01*
X778700Y-15667D01*
X779400Y-15800D01*
X780000Y-16333D01*
X780300Y-17267D01*
Y-21000D01*
G01X785200Y-23000D02*
X785900Y-23533D01*
X786700Y-23667D01*
X787400Y-23533D01*
X788000Y-22867D01*
X788400Y-21933D01*
Y-15667D01*
G01Y-16733D02*
X788000Y-16200D01*
X787400Y-15800D01*
X786700Y-15667D01*
X785900Y-15933D01*
X785400Y-16467D01*
X785000Y-17400D01*
X784800Y-18333D01*
X784900Y-19133D01*
X785300Y-20067D01*
X785900Y-20733D01*
X786700Y-21000D01*
X787300Y-20867D01*
X788000Y-20333D01*
X788400Y-19800D01*
G01X795100Y-23667D02*
X796100Y-22333D01*
X796600Y-21000D01*
Y-15667D01*
X796100Y-14333D01*
X795100Y-13000D01*
G01X464600Y-8500D02*
Y-500D01*
X467000D01*
X467800Y-900D01*
X468400Y-1833D01*
X468600Y-2900D01*
X468400Y-3967D01*
X467900Y-4767D01*
X467000Y-5167D01*
X464600D01*
G01X474600Y-8500D02*
Y-500D01*
G01X480900Y-3167D02*
Y-6900D01*
X481300Y-7833D01*
X481900Y-8367D01*
X482600Y-8500D01*
X483300Y-8367D01*
X483900Y-7833D01*
X484300Y-6900D01*
G01Y-8500D02*
Y-3167D01*
G01X489200Y-10500D02*
X489900Y-11033D01*
X490700Y-11167D01*
X491400Y-11033D01*
X492000Y-10367D01*
X492400Y-9433D01*
Y-3167D01*
G01Y-4233D02*
X492000Y-3700D01*
X491400Y-3300D01*
X490700Y-3167D01*
X489900Y-3433D01*
X489400Y-3967D01*
X489000Y-4900D01*
X488800Y-5833D01*
X488900Y-6633D01*
X489300Y-7567D01*
X489900Y-8233D01*
X490700Y-8500D01*
X491300Y-8367D01*
X492000Y-7833D01*
X492400Y-7300D01*
G01X497200Y-10500D02*
X497900Y-11033D01*
X498700Y-11167D01*
X499400Y-11033D01*
X500000Y-10367D01*
X500400Y-9433D01*
Y-3167D01*
G01Y-4233D02*
X500000Y-3700D01*
X499400Y-3300D01*
X498700Y-3167D01*
X497900Y-3433D01*
X497400Y-3967D01*
X497000Y-4900D01*
X496800Y-5833D01*
X496900Y-6633D01*
X497300Y-7567D01*
X497900Y-8233D01*
X498700Y-8500D01*
X499300Y-8367D01*
X500000Y-7833D01*
X500400Y-7300D01*
G01X505100Y-4900D02*
X508300D01*
X508000Y-3967D01*
X507500Y-3433D01*
X506800Y-3167D01*
X506100Y-3300D01*
X505500Y-3700D01*
X505100Y-4633D01*
X504900Y-5434D01*
Y-6233D01*
X505100Y-7033D01*
X505600Y-7833D01*
X506200Y-8367D01*
X506900Y-8500D01*
X507600Y-8233D01*
X508300Y-7434D01*
G01X516400Y-500D02*
Y-8500D01*
G01Y-7300D02*
X516000Y-7967D01*
X515400Y-8367D01*
X514700Y-8500D01*
X513900Y-8233D01*
X513300Y-7567D01*
X512900Y-6767D01*
X512800Y-5833D01*
X512900Y-4900D01*
X513300Y-4100D01*
X513900Y-3433D01*
X514700Y-3167D01*
X515400Y-3300D01*
X515900Y-3567D01*
X516400Y-4100D01*
G01X528600Y-8500D02*
Y-500D01*
X531000D01*
X531800Y-900D01*
X532400Y-1833D01*
X532600Y-2900D01*
X532400Y-3967D01*
X531900Y-4767D01*
X531000Y-5167D01*
X528600D01*
G01X538600Y-500D02*
Y-8500D01*
G01X536300Y-500D02*
X540900D01*
G01X544500Y-8500D02*
Y-500D01*
G01X548700D02*
Y-8500D01*
G01Y-4500D02*
X544500D01*
G01X554100Y-11167D02*
X553100Y-9833D01*
X552600Y-8500D01*
Y-3167D01*
X553100Y-1833D01*
X554100Y-500D01*
G01X560900Y-8500D02*
Y-500D01*
G01Y-4367D02*
X561400Y-3700D01*
X561900Y-3300D01*
X562700Y-3167D01*
X563300Y-3300D01*
X564000Y-3833D01*
X564300Y-4633D01*
Y-8500D01*
G01X570600D02*
X570000Y-8367D01*
X569400Y-7833D01*
X569000Y-6900D01*
X568800Y-5833D01*
X569000Y-4767D01*
X569400Y-3833D01*
X570000Y-3300D01*
X570600Y-3167D01*
X571200Y-3300D01*
X571800Y-3833D01*
X572200Y-4767D01*
X572300Y-5833D01*
X572200Y-6900D01*
X571800Y-7833D01*
X571200Y-8367D01*
X570600Y-8500D01*
G01X578600D02*
Y-500D01*
G01X585100Y-4900D02*
X588300D01*
X588000Y-3967D01*
X587500Y-3433D01*
X586800Y-3167D01*
X586100Y-3300D01*
X585500Y-3700D01*
X585100Y-4633D01*
X584900Y-5434D01*
Y-6233D01*
X585100Y-7033D01*
X585600Y-7833D01*
X586200Y-8367D01*
X586900Y-8500D01*
X587600Y-8233D01*
X588300Y-7434D01*
G01X601100Y-7567D02*
X601600Y-8100D01*
X602300Y-8500D01*
X602900D01*
X603500Y-8233D01*
X603900Y-7833D01*
X604100Y-7300D01*
X604000Y-6500D01*
X603600Y-6100D01*
X601800Y-5300D01*
X601400Y-4367D01*
X601600Y-3700D01*
X602000Y-3300D01*
X602600Y-3167D01*
X603200Y-3300D01*
X603800Y-3700D01*
G01X610600Y-3167D02*
Y-8500D01*
G01Y-1033D02*
X610400Y-900D01*
Y-633D01*
X610600Y-500D01*
X610800Y-633D01*
Y-900D01*
X610600Y-1033D01*
G01X617100Y-3167D02*
X620100D01*
X617100Y-8500D01*
X620100D01*
G01X625100Y-4900D02*
X628300D01*
X628000Y-3967D01*
X627500Y-3433D01*
X626800Y-3167D01*
X626100Y-3300D01*
X625500Y-3700D01*
X625100Y-4633D01*
X624900Y-5434D01*
Y-6233D01*
X625100Y-7033D01*
X625600Y-7833D01*
X626200Y-8367D01*
X626900Y-8500D01*
X627600Y-8233D01*
X628300Y-7434D01*
G01X632600Y-8500D02*
X636600Y-5833D01*
X632600Y-3167D01*
G01X641300Y-7033D02*
X643900D01*
G01Y-4633D02*
X641300D01*
G01X650600Y-8500D02*
Y-500D01*
X649400Y-2100D01*
G01Y-8500D02*
X651800D01*
G01X656700Y-5167D02*
X657400Y-4233D01*
X658000Y-3700D01*
X658800Y-3433D01*
X659500Y-3700D01*
X660000Y-4233D01*
X660400Y-5033D01*
X660500Y-5967D01*
X660400Y-6767D01*
X660000Y-7567D01*
X659400Y-8233D01*
X658700Y-8500D01*
X657900Y-8233D01*
X657200Y-7434D01*
X656800Y-6233D01*
X656700Y-4900D01*
X656900Y-3167D01*
X657200Y-2233D01*
X657700Y-1300D01*
X658400Y-633D01*
X659100Y-500D01*
X659800Y-767D01*
X660300Y-1433D01*
G01X671600Y-8500D02*
Y-3167D01*
G01Y-4633D02*
X671900Y-3967D01*
X672400Y-3433D01*
X673100Y-3167D01*
X673800Y-3433D01*
X674300Y-3967D01*
X674600Y-4633D01*
Y-8500D01*
G01Y-4633D02*
X674900Y-3967D01*
X675400Y-3433D01*
X676100Y-3167D01*
X676800Y-3433D01*
X677300Y-3967D01*
X677600Y-4767D01*
Y-8500D01*
G01X682600Y-3167D02*
Y-8500D01*
G01Y-1033D02*
X682400Y-900D01*
Y-633D01*
X682600Y-500D01*
X682800Y-633D01*
Y-900D01*
X682600Y-1033D01*
G01X690600Y-8500D02*
Y-500D01*
G01X699100Y-11167D02*
X700100Y-9833D01*
X700600Y-8500D01*
Y-3167D01*
X700100Y-1833D01*
X699100Y-500D01*
G01X464600Y4000D02*
Y12000D01*
X467000D01*
X467800Y11600D01*
X468400Y10667D01*
X468600Y9600D01*
X468400Y8533D01*
X467900Y7733D01*
X467000Y7333D01*
X464600D01*
G01X474600Y4000D02*
Y12000D01*
G01X480900Y9333D02*
Y5600D01*
X481300Y4667D01*
X481900Y4133D01*
X482600Y4000D01*
X483300Y4133D01*
X483900Y4667D01*
X484300Y5600D01*
G01Y4000D02*
Y9333D01*
G01X489200Y2000D02*
X489900Y1467D01*
X490700Y1333D01*
X491400Y1467D01*
X492000Y2133D01*
X492400Y3067D01*
Y9333D01*
G01Y8267D02*
X492000Y8800D01*
X491400Y9200D01*
X490700Y9333D01*
X489900Y9067D01*
X489400Y8533D01*
X489000Y7600D01*
X488800Y6667D01*
X488900Y5867D01*
X489300Y4933D01*
X489900Y4267D01*
X490700Y4000D01*
X491300Y4133D01*
X492000Y4667D01*
X492400Y5200D01*
G01X497200Y2000D02*
X497900Y1467D01*
X498700Y1333D01*
X499400Y1467D01*
X500000Y2133D01*
X500400Y3067D01*
Y9333D01*
G01Y8267D02*
X500000Y8800D01*
X499400Y9200D01*
X498700Y9333D01*
X497900Y9067D01*
X497400Y8533D01*
X497000Y7600D01*
X496800Y6667D01*
X496900Y5867D01*
X497300Y4933D01*
X497900Y4267D01*
X498700Y4000D01*
X499300Y4133D01*
X500000Y4667D01*
X500400Y5200D01*
G01X505100Y7600D02*
X508300D01*
X508000Y8533D01*
X507500Y9067D01*
X506800Y9333D01*
X506100Y9200D01*
X505500Y8800D01*
X505100Y7867D01*
X504900Y7066D01*
Y6267D01*
X505100Y5467D01*
X505600Y4667D01*
X506200Y4133D01*
X506900Y4000D01*
X507600Y4267D01*
X508300Y5066D01*
G01X516400Y12000D02*
Y4000D01*
G01Y5200D02*
X516000Y4533D01*
X515400Y4133D01*
X514700Y4000D01*
X513900Y4267D01*
X513300Y4933D01*
X512900Y5733D01*
X512800Y6667D01*
X512900Y7600D01*
X513300Y8400D01*
X513900Y9067D01*
X514700Y9333D01*
X515400Y9200D01*
X515900Y8933D01*
X516400Y8400D01*
G01X528100Y12000D02*
X530600Y4000D01*
X533100Y12000D01*
G01X538600Y9333D02*
Y4000D01*
G01Y11467D02*
X538400Y11600D01*
Y11867D01*
X538600Y12000D01*
X538800Y11867D01*
Y11600D01*
X538600Y11467D01*
G01X548400Y4000D02*
Y9333D01*
G01Y8400D02*
X548000Y8933D01*
X547400Y9200D01*
X546700Y9333D01*
X546000Y9067D01*
X545400Y8533D01*
X545000Y7733D01*
X544800Y6667D01*
X545000Y5600D01*
X545400Y4800D01*
X546000Y4267D01*
X546700Y4000D01*
X547400Y4133D01*
X548000Y4533D01*
X548400Y5066D01*
G01X554100Y1333D02*
X553100Y2667D01*
X552600Y4000D01*
Y9333D01*
X553100Y10667D01*
X554100Y12000D01*
G01X560900Y4000D02*
Y12000D01*
G01Y8133D02*
X561400Y8800D01*
X561900Y9200D01*
X562700Y9333D01*
X563300Y9200D01*
X564000Y8667D01*
X564300Y7867D01*
Y4000D01*
G01X570600D02*
X570000Y4133D01*
X569400Y4667D01*
X569000Y5600D01*
X568800Y6667D01*
X569000Y7733D01*
X569400Y8667D01*
X570000Y9200D01*
X570600Y9333D01*
X571200Y9200D01*
X571800Y8667D01*
X572200Y7733D01*
X572300Y6667D01*
X572200Y5600D01*
X571800Y4667D01*
X571200Y4133D01*
X570600Y4000D01*
G01X578600D02*
Y12000D01*
G01X585100Y7600D02*
X588300D01*
X588000Y8533D01*
X587500Y9067D01*
X586800Y9333D01*
X586100Y9200D01*
X585500Y8800D01*
X585100Y7867D01*
X584900Y7066D01*
Y6267D01*
X585100Y5467D01*
X585600Y4667D01*
X586200Y4133D01*
X586900Y4000D01*
X587600Y4267D01*
X588300Y5066D01*
G01X601100Y4933D02*
X601600Y4400D01*
X602300Y4000D01*
X602900D01*
X603500Y4267D01*
X603900Y4667D01*
X604100Y5200D01*
X604000Y6000D01*
X603600Y6400D01*
X601800Y7200D01*
X601400Y8133D01*
X601600Y8800D01*
X602000Y9200D01*
X602600Y9333D01*
X603200Y9200D01*
X603800Y8800D01*
G01X610600Y9333D02*
Y4000D01*
G01Y11467D02*
X610400Y11600D01*
Y11867D01*
X610600Y12000D01*
X610800Y11867D01*
Y11600D01*
X610600Y11467D01*
G01X617100Y9333D02*
X620100D01*
X617100Y4000D01*
X620100D01*
G01X625100Y7600D02*
X628300D01*
X628000Y8533D01*
X627500Y9067D01*
X626800Y9333D01*
X626100Y9200D01*
X625500Y8800D01*
X625100Y7867D01*
X624900Y7066D01*
Y6267D01*
X625100Y5467D01*
X625600Y4667D01*
X626200Y4133D01*
X626900Y4000D01*
X627600Y4267D01*
X628300Y5066D01*
G01X636600Y4000D02*
X632600Y6667D01*
X636600Y9333D01*
G01X642600Y4000D02*
Y12000D01*
X641400Y10400D01*
G01Y4000D02*
X643800D01*
G01X648700Y7333D02*
X649400Y8267D01*
X650000Y8800D01*
X650800Y9067D01*
X651500Y8800D01*
X652000Y8267D01*
X652400Y7467D01*
X652500Y6533D01*
X652400Y5733D01*
X652000Y4933D01*
X651400Y4267D01*
X650700Y4000D01*
X649900Y4267D01*
X649200Y5066D01*
X648800Y6267D01*
X648700Y7600D01*
X648900Y9333D01*
X649200Y10267D01*
X649700Y11200D01*
X650400Y11867D01*
X651100Y12000D01*
X651800Y11733D01*
X652300Y11067D01*
G01X663600Y4000D02*
Y9333D01*
G01Y7867D02*
X663900Y8533D01*
X664400Y9067D01*
X665100Y9333D01*
X665800Y9067D01*
X666300Y8533D01*
X666600Y7867D01*
Y4000D01*
G01Y7867D02*
X666900Y8533D01*
X667400Y9067D01*
X668100Y9333D01*
X668800Y9067D01*
X669300Y8533D01*
X669600Y7733D01*
Y4000D01*
G01X674600Y9333D02*
Y4000D01*
G01Y11467D02*
X674400Y11600D01*
Y11867D01*
X674600Y12000D01*
X674800Y11867D01*
Y11600D01*
X674600Y11467D01*
G01X682600Y4000D02*
Y12000D01*
G01X691100Y1333D02*
X692100Y2667D01*
X692600Y4000D01*
Y9333D01*
X692100Y10667D01*
X691100Y12000D01*
G01X466000Y-120500D02*
Y-112500D01*
G01X470200D02*
Y-120500D01*
G01Y-116500D02*
X466000D01*
G01X476100Y-120500D02*
X475500Y-120367D01*
X474900Y-119833D01*
X474500Y-118900D01*
X474300Y-117833D01*
X474500Y-116767D01*
X474900Y-115833D01*
X475500Y-115300D01*
X476100Y-115167D01*
X476700Y-115300D01*
X477300Y-115833D01*
X477700Y-116767D01*
X477800Y-117833D01*
X477700Y-118900D01*
X477300Y-119833D01*
X476700Y-120367D01*
X476100Y-120500D01*
G01X484100D02*
Y-112500D01*
G01X490600Y-116900D02*
X493800D01*
X493500Y-115967D01*
X493000Y-115433D01*
X492300Y-115167D01*
X491600Y-115300D01*
X491000Y-115700D01*
X490600Y-116633D01*
X490400Y-117434D01*
Y-118233D01*
X490600Y-119033D01*
X491100Y-119833D01*
X491700Y-120367D01*
X492400Y-120500D01*
X493100Y-120233D01*
X493800Y-119434D01*
G01X505100Y-112500D02*
X506500Y-120500D01*
X508100Y-112500D01*
X509700Y-120500D01*
X511100Y-112500D01*
G01X517900Y-120500D02*
Y-115167D01*
G01Y-116100D02*
X517500Y-115567D01*
X516900Y-115300D01*
X516200Y-115167D01*
X515500Y-115433D01*
X514900Y-115967D01*
X514500Y-116767D01*
X514300Y-117833D01*
X514500Y-118900D01*
X514900Y-119700D01*
X515500Y-120233D01*
X516200Y-120500D01*
X516900Y-120367D01*
X517500Y-119967D01*
X517900Y-119434D01*
G01X524100Y-120500D02*
Y-112500D01*
G01X532100Y-120500D02*
Y-112500D01*
G01X546100Y-120500D02*
Y-112500D01*
X548600D01*
X549400Y-112900D01*
X549900Y-113433D01*
X550100Y-114500D01*
X549900Y-115567D01*
X549300Y-116233D01*
X548600Y-116633D01*
X546100D01*
G01X548600D02*
X550100Y-120500D01*
G01X556100D02*
X555500Y-120367D01*
X554900Y-119833D01*
X554500Y-118900D01*
X554300Y-117833D01*
X554500Y-116767D01*
X554900Y-115833D01*
X555500Y-115300D01*
X556100Y-115167D01*
X556700Y-115300D01*
X557300Y-115833D01*
X557700Y-116767D01*
X557800Y-117833D01*
X557700Y-118900D01*
X557300Y-119833D01*
X556700Y-120367D01*
X556100Y-120500D01*
G01X562400Y-115167D02*
Y-118900D01*
X562800Y-119833D01*
X563400Y-120367D01*
X564100Y-120500D01*
X564800Y-120367D01*
X565400Y-119833D01*
X565800Y-118900D01*
G01Y-120500D02*
Y-115167D01*
G01X570700Y-122500D02*
X571400Y-123033D01*
X572200Y-123167D01*
X572900Y-123033D01*
X573500Y-122367D01*
X573900Y-121433D01*
Y-115167D01*
G01Y-116233D02*
X573500Y-115700D01*
X572900Y-115300D01*
X572200Y-115167D01*
X571400Y-115433D01*
X570900Y-115967D01*
X570500Y-116900D01*
X570300Y-117833D01*
X570400Y-118633D01*
X570800Y-119567D01*
X571400Y-120233D01*
X572200Y-120500D01*
X572800Y-120367D01*
X573500Y-119833D01*
X573900Y-119300D01*
G01X578400Y-120500D02*
Y-112500D01*
G01Y-116367D02*
X578900Y-115700D01*
X579400Y-115300D01*
X580200Y-115167D01*
X580800Y-115300D01*
X581500Y-115833D01*
X581800Y-116633D01*
Y-120500D01*
G01X586400D02*
Y-115167D01*
G01Y-116500D02*
X586800Y-115833D01*
X587400Y-115300D01*
X588200Y-115167D01*
X588900Y-115300D01*
X589500Y-115833D01*
X589800Y-116767D01*
Y-120500D01*
G01X594600Y-116900D02*
X597800D01*
X597500Y-115967D01*
X597000Y-115433D01*
X596300Y-115167D01*
X595600Y-115300D01*
X595000Y-115700D01*
X594600Y-116633D01*
X594400Y-117434D01*
Y-118233D01*
X594600Y-119033D01*
X595100Y-119833D01*
X595700Y-120367D01*
X596400Y-120500D01*
X597100Y-120233D01*
X597800Y-119434D01*
G01X602600Y-119567D02*
X603100Y-120100D01*
X603800Y-120500D01*
X604400D01*
X605000Y-120233D01*
X605400Y-119833D01*
X605600Y-119300D01*
X605500Y-118500D01*
X605100Y-118100D01*
X603300Y-117300D01*
X602900Y-116367D01*
X603100Y-115700D01*
X603500Y-115300D01*
X604100Y-115167D01*
X604700Y-115300D01*
X605300Y-115700D01*
G01X610600Y-119567D02*
X611100Y-120100D01*
X611800Y-120500D01*
X612400D01*
X613000Y-120233D01*
X613400Y-119833D01*
X613600Y-119300D01*
X613500Y-118500D01*
X613100Y-118100D01*
X611300Y-117300D01*
X610900Y-116367D01*
X611100Y-115700D01*
X611500Y-115300D01*
X612100Y-115167D01*
X612700Y-115300D01*
X613300Y-115700D01*
G01X467100Y-108500D02*
X466300Y-108367D01*
X465600Y-107833D01*
X465000Y-107033D01*
X464600Y-106100D01*
X464400Y-105033D01*
Y-103967D01*
X464600Y-102900D01*
X465000Y-101967D01*
X465600Y-101167D01*
X466300Y-100633D01*
X467100Y-100500D01*
X467900Y-100633D01*
X468600Y-101167D01*
X469200Y-101967D01*
X469600Y-102900D01*
X469800Y-103967D01*
Y-105033D01*
X469600Y-106100D01*
X469200Y-107033D01*
X468600Y-107833D01*
X467900Y-108367D01*
X467100Y-108500D01*
G01X475100Y-100500D02*
Y-108500D01*
G01X473700Y-103167D02*
X476500D01*
G01X481400Y-108500D02*
Y-100500D01*
G01Y-104367D02*
X481900Y-103700D01*
X482400Y-103300D01*
X483200Y-103167D01*
X483800Y-103300D01*
X484500Y-103833D01*
X484800Y-104633D01*
Y-108500D01*
G01X489600Y-104900D02*
X492800D01*
X492500Y-103967D01*
X492000Y-103433D01*
X491300Y-103167D01*
X490600Y-103300D01*
X490000Y-103700D01*
X489600Y-104633D01*
X489400Y-105434D01*
Y-106233D01*
X489600Y-107033D01*
X490100Y-107833D01*
X490700Y-108367D01*
X491400Y-108500D01*
X492100Y-108233D01*
X492800Y-107434D01*
G01X497700Y-108500D02*
Y-103167D01*
G01Y-104233D02*
X498200Y-103700D01*
X498700Y-103300D01*
X499400Y-103167D01*
X499900Y-103300D01*
X500500Y-103700D01*
G01X505600Y-107567D02*
X506100Y-108100D01*
X506800Y-108500D01*
X507400D01*
X508000Y-108233D01*
X508400Y-107833D01*
X508600Y-107300D01*
X508500Y-106500D01*
X508100Y-106100D01*
X506300Y-105300D01*
X505900Y-104367D01*
X506100Y-103700D01*
X506500Y-103300D01*
X507100Y-103167D01*
X507700Y-103300D01*
X508300Y-103700D01*
G01X522600Y-111167D02*
X521600Y-109833D01*
X521100Y-108500D01*
Y-103167D01*
X521600Y-101833D01*
X522600Y-100500D01*
G01X531100Y-108500D02*
Y-100500D01*
G01X539100Y-103167D02*
Y-108500D01*
G01Y-101033D02*
X538900Y-100900D01*
Y-100633D01*
X539100Y-100500D01*
X539300Y-100633D01*
Y-100900D01*
X539100Y-101033D01*
G01X545400Y-108500D02*
Y-100500D01*
G01X548600Y-103167D02*
X545400Y-106233D01*
G01X546700Y-105033D02*
X548800Y-108500D01*
G01X553600Y-104900D02*
X556800D01*
X556500Y-103967D01*
X556000Y-103433D01*
X555300Y-103167D01*
X554600Y-103300D01*
X554000Y-103700D01*
X553600Y-104633D01*
X553400Y-105434D01*
Y-106233D01*
X553600Y-107033D01*
X554100Y-107833D01*
X554700Y-108367D01*
X555400Y-108500D01*
X556100Y-108233D01*
X556800Y-107434D01*
G01X569600Y-104900D02*
X572800D01*
X572500Y-103967D01*
X572000Y-103433D01*
X571300Y-103167D01*
X570600Y-103300D01*
X570000Y-103700D01*
X569600Y-104633D01*
X569400Y-105434D01*
Y-106233D01*
X569600Y-107033D01*
X570100Y-107833D01*
X570700Y-108367D01*
X571400Y-108500D01*
X572100Y-108233D01*
X572800Y-107434D01*
G01X579100Y-108500D02*
Y-100500D01*
G01X587100Y-108500D02*
Y-100500D01*
G01X595100Y-103167D02*
Y-108500D01*
G01Y-101033D02*
X594900Y-100900D01*
Y-100633D01*
X595100Y-100500D01*
X595300Y-100633D01*
Y-100900D01*
X595100Y-101033D01*
G01X601300Y-111167D02*
Y-103167D01*
G01Y-104367D02*
X601800Y-103700D01*
X602300Y-103300D01*
X603100Y-103167D01*
X603800Y-103300D01*
X604500Y-103967D01*
X604800Y-104900D01*
X604900Y-105833D01*
X604800Y-106767D01*
X604500Y-107700D01*
X603900Y-108233D01*
X603100Y-108500D01*
X602400Y-108367D01*
X601700Y-107967D01*
X601300Y-107434D01*
G01X609600Y-107567D02*
X610100Y-108100D01*
X610800Y-108500D01*
X611400D01*
X612000Y-108233D01*
X612400Y-107833D01*
X612600Y-107300D01*
X612500Y-106500D01*
X612100Y-106100D01*
X610300Y-105300D01*
X609900Y-104367D01*
X610100Y-103700D01*
X610500Y-103300D01*
X611100Y-103167D01*
X611700Y-103300D01*
X612300Y-103700D01*
G01X617600Y-104900D02*
X620800D01*
X620500Y-103967D01*
X620000Y-103433D01*
X619300Y-103167D01*
X618600Y-103300D01*
X618000Y-103700D01*
X617600Y-104633D01*
X617400Y-105434D01*
Y-106233D01*
X617600Y-107033D01*
X618100Y-107833D01*
X618700Y-108367D01*
X619400Y-108500D01*
X620100Y-108233D01*
X620800Y-107434D01*
G01X636900Y-108500D02*
Y-103167D01*
G01Y-104100D02*
X636500Y-103567D01*
X635900Y-103300D01*
X635200Y-103167D01*
X634500Y-103433D01*
X633900Y-103967D01*
X633500Y-104767D01*
X633300Y-105833D01*
X633500Y-106900D01*
X633900Y-107700D01*
X634500Y-108233D01*
X635200Y-108500D01*
X635900Y-108367D01*
X636500Y-107967D01*
X636900Y-107434D01*
G01X641400Y-108500D02*
Y-103167D01*
G01Y-104500D02*
X641800Y-103833D01*
X642400Y-103300D01*
X643200Y-103167D01*
X643900Y-103300D01*
X644500Y-103833D01*
X644800Y-104767D01*
Y-108500D01*
G01X652900Y-100500D02*
Y-108500D01*
G01Y-107300D02*
X652500Y-107967D01*
X651900Y-108367D01*
X651200Y-108500D01*
X650400Y-108233D01*
X649800Y-107567D01*
X649400Y-106767D01*
X649300Y-105833D01*
X649400Y-104900D01*
X649800Y-104100D01*
X650400Y-103433D01*
X651200Y-103167D01*
X651900Y-103300D01*
X652400Y-103567D01*
X652900Y-104100D01*
G01X667100Y-108500D02*
X666500Y-108367D01*
X665900Y-107833D01*
X665500Y-106900D01*
X665300Y-105833D01*
X665500Y-104767D01*
X665900Y-103833D01*
X666500Y-103300D01*
X667100Y-103167D01*
X667700Y-103300D01*
X668300Y-103833D01*
X668700Y-104767D01*
X668800Y-105833D01*
X668700Y-106900D01*
X668300Y-107833D01*
X667700Y-108367D01*
X667100Y-108500D01*
G01X675100Y-100500D02*
Y-108500D01*
G01X673700Y-103167D02*
X676500D01*
G01X681400Y-108500D02*
Y-100500D01*
G01Y-104367D02*
X681900Y-103700D01*
X682400Y-103300D01*
X683200Y-103167D01*
X683800Y-103300D01*
X684500Y-103833D01*
X684800Y-104633D01*
Y-108500D01*
G01X689600Y-104900D02*
X692800D01*
X692500Y-103967D01*
X692000Y-103433D01*
X691300Y-103167D01*
X690600Y-103300D01*
X690000Y-103700D01*
X689600Y-104633D01*
X689400Y-105434D01*
Y-106233D01*
X689600Y-107033D01*
X690100Y-107833D01*
X690700Y-108367D01*
X691400Y-108500D01*
X692100Y-108233D01*
X692800Y-107434D01*
G01X697700Y-108500D02*
Y-103167D01*
G01Y-104233D02*
X698200Y-103700D01*
X698700Y-103300D01*
X699400Y-103167D01*
X699900Y-103300D01*
X700500Y-103700D01*
G01X705600Y-107567D02*
X706100Y-108100D01*
X706800Y-108500D01*
X707400D01*
X708000Y-108233D01*
X708400Y-107833D01*
X708600Y-107300D01*
X708500Y-106500D01*
X708100Y-106100D01*
X706300Y-105300D01*
X705900Y-104367D01*
X706100Y-103700D01*
X706500Y-103300D01*
X707100Y-103167D01*
X707700Y-103300D01*
X708300Y-103700D01*
G01X715600Y-111167D02*
X716600Y-109833D01*
X717100Y-108500D01*
Y-103167D01*
X716600Y-101833D01*
X715600Y-100500D01*
G01X465100Y-97000D02*
Y-89000D01*
X467500D01*
X468300Y-89400D01*
X468900Y-90333D01*
X469100Y-91400D01*
X468900Y-92467D01*
X468400Y-93267D01*
X467500Y-93667D01*
X465100D01*
G01X475100Y-89000D02*
Y-97000D01*
G01X472800Y-89000D02*
X477400D01*
G01X481000Y-97000D02*
Y-89000D01*
G01X485200D02*
Y-97000D01*
G01Y-93000D02*
X481000D01*
G01X489300Y-97267D02*
X492900Y-89000D01*
G01X496800Y-97000D02*
Y-89000D01*
X501400Y-97000D01*
Y-89000D01*
G01X505100Y-97000D02*
Y-89000D01*
X507500D01*
X508300Y-89400D01*
X508900Y-90333D01*
X509100Y-91400D01*
X508900Y-92467D01*
X508400Y-93267D01*
X507500Y-93667D01*
X505100D01*
G01X515100Y-89000D02*
Y-97000D01*
G01X512800Y-89000D02*
X517400D01*
G01X521000Y-97000D02*
Y-89000D01*
G01X525200D02*
Y-97000D01*
G01Y-93000D02*
X521000D01*
G01X537100Y-97000D02*
X541100Y-94333D01*
X537100Y-91667D01*
G01X545800Y-95533D02*
X548400D01*
G01Y-93133D02*
X545800D01*
G01X552900Y-95800D02*
X553500Y-96467D01*
X554200Y-96867D01*
X555100Y-97000D01*
X556000Y-96733D01*
X556700Y-96200D01*
X557200Y-95267D01*
X557300Y-94200D01*
X557100Y-93133D01*
X556600Y-92467D01*
X555900Y-91933D01*
X555200Y-91800D01*
X554500Y-91933D01*
X553600Y-92467D01*
X553900Y-89000D01*
X556600D01*
G01X568100Y-97000D02*
Y-91667D01*
G01Y-93133D02*
X568400Y-92467D01*
X568900Y-91933D01*
X569600Y-91667D01*
X570300Y-91933D01*
X570800Y-92467D01*
X571100Y-93133D01*
Y-97000D01*
G01Y-93133D02*
X571400Y-92467D01*
X571900Y-91933D01*
X572600Y-91667D01*
X573300Y-91933D01*
X573800Y-92467D01*
X574100Y-93267D01*
Y-97000D01*
G01X576100D02*
Y-91667D01*
G01Y-93133D02*
X576400Y-92467D01*
X576900Y-91933D01*
X577600Y-91667D01*
X578300Y-91933D01*
X578800Y-92467D01*
X579100Y-93133D01*
Y-97000D01*
G01Y-93133D02*
X579400Y-92467D01*
X579900Y-91933D01*
X580600Y-91667D01*
X581300Y-91933D01*
X581800Y-92467D01*
X582100Y-93267D01*
Y-97000D01*
G01X465300Y-84000D02*
Y-76000D01*
X469900Y-84000D01*
Y-76000D01*
G01X473600Y-84000D02*
Y-76000D01*
X476000D01*
X476800Y-76400D01*
X477400Y-77333D01*
X477600Y-78400D01*
X477400Y-79467D01*
X476900Y-80267D01*
X476000Y-80667D01*
X473600D01*
G01X483600Y-76000D02*
Y-84000D01*
G01X481300Y-76000D02*
X485900D01*
G01X489500Y-84000D02*
Y-76000D01*
G01X493700D02*
Y-84000D01*
G01Y-80000D02*
X489500D01*
G01X505500Y-82934D02*
X506300Y-83600D01*
X507200Y-84000D01*
X508000D01*
X508800Y-83600D01*
X509400Y-82934D01*
X509700Y-82000D01*
X509500Y-81067D01*
X509000Y-80267D01*
X508100Y-79733D01*
X506900Y-79467D01*
X506200Y-78933D01*
X505900Y-78000D01*
X506100Y-77067D01*
X506600Y-76400D01*
X507300Y-76000D01*
X508000D01*
X508700Y-76267D01*
X509300Y-76933D01*
G01X515600Y-78667D02*
Y-84000D01*
G01Y-76533D02*
X515400Y-76400D01*
Y-76133D01*
X515600Y-76000D01*
X515800Y-76133D01*
Y-76400D01*
X515600Y-76533D01*
G01X522100Y-78667D02*
X525100D01*
X522100Y-84000D01*
X525100D01*
G01X530100Y-80400D02*
X533300D01*
X533000Y-79467D01*
X532500Y-78933D01*
X531800Y-78667D01*
X531100Y-78800D01*
X530500Y-79200D01*
X530100Y-80133D01*
X529900Y-80934D01*
Y-81733D01*
X530100Y-82533D01*
X530600Y-83333D01*
X531200Y-83867D01*
X531900Y-84000D01*
X532600Y-83733D01*
X533300Y-82934D01*
G01X545700Y-77333D02*
X546300Y-76533D01*
X547000Y-76133D01*
X547800Y-76000D01*
X548800Y-76267D01*
X549500Y-76933D01*
X549700Y-77733D01*
X549600Y-78534D01*
X549200Y-79200D01*
X547200Y-80533D01*
X546300Y-81467D01*
X545700Y-82800D01*
X545500Y-84000D01*
X549700D01*
G01X555600Y-84267D02*
X555400Y-84133D01*
Y-83867D01*
X555600Y-83733D01*
X555800Y-83867D01*
Y-84133D01*
X555600Y-84267D01*
G01X563600Y-84000D02*
Y-76000D01*
X562400Y-77600D01*
G01Y-84000D02*
X564800D01*
G01X571600D02*
X572300Y-83867D01*
X573100Y-83467D01*
X573600Y-82800D01*
X573800Y-81867D01*
X573600Y-80934D01*
X573000Y-80133D01*
X572100Y-79733D01*
X571100D01*
X570500Y-79467D01*
X570000Y-78800D01*
X569800Y-77867D01*
X570100Y-76933D01*
X570800Y-76267D01*
X571600Y-76000D01*
X572400Y-76267D01*
X573100Y-76933D01*
X573400Y-77867D01*
X573200Y-78800D01*
X572700Y-79467D01*
X572100Y-79733D01*
X571100D01*
X570200Y-80133D01*
X569600Y-80934D01*
X569400Y-81867D01*
X569600Y-82800D01*
X570100Y-83467D01*
X570900Y-83867D01*
X571600Y-84000D01*
G01X576600D02*
Y-78667D01*
G01Y-80133D02*
X576900Y-79467D01*
X577400Y-78933D01*
X578100Y-78667D01*
X578800Y-78933D01*
X579300Y-79467D01*
X579600Y-80133D01*
Y-84000D01*
G01Y-80133D02*
X579900Y-79467D01*
X580400Y-78933D01*
X581100Y-78667D01*
X581800Y-78933D01*
X582300Y-79467D01*
X582600Y-80267D01*
Y-84000D01*
G01X584600D02*
Y-78667D01*
G01Y-80133D02*
X584900Y-79467D01*
X585400Y-78933D01*
X586100Y-78667D01*
X586800Y-78933D01*
X587300Y-79467D01*
X587600Y-80133D01*
Y-84000D01*
G01Y-80133D02*
X587900Y-79467D01*
X588400Y-78933D01*
X589100Y-78667D01*
X589800Y-78933D01*
X590300Y-79467D01*
X590600Y-80267D01*
Y-84000D01*
G01X603100Y-86667D02*
X602100Y-85333D01*
X601600Y-84000D01*
Y-78667D01*
X602100Y-77333D01*
X603100Y-76000D01*
G01X611600Y-84000D02*
X611000Y-83867D01*
X610400Y-83333D01*
X610000Y-82400D01*
X609800Y-81333D01*
X610000Y-80267D01*
X610400Y-79333D01*
X611000Y-78800D01*
X611600Y-78667D01*
X612200Y-78800D01*
X612800Y-79333D01*
X613200Y-80267D01*
X613300Y-81333D01*
X613200Y-82400D01*
X612800Y-83333D01*
X612200Y-83867D01*
X611600Y-84000D01*
G01X617900D02*
Y-78667D01*
G01Y-80000D02*
X618300Y-79333D01*
X618900Y-78800D01*
X619700Y-78667D01*
X620400Y-78800D01*
X621000Y-79333D01*
X621300Y-80267D01*
Y-84000D01*
G01X633800D02*
Y-76000D01*
G01Y-80000D02*
X634300Y-79200D01*
X634900Y-78800D01*
X635500Y-78667D01*
X636400Y-78933D01*
X637000Y-79467D01*
X637400Y-80400D01*
Y-81467D01*
X637200Y-82533D01*
X636800Y-83333D01*
X636100Y-83867D01*
X635500Y-84000D01*
X634900Y-83867D01*
X634300Y-83467D01*
X633800Y-82800D01*
G01X642200Y-84000D02*
Y-78667D01*
G01Y-79733D02*
X642700Y-79200D01*
X643200Y-78800D01*
X643900Y-78667D01*
X644400Y-78800D01*
X645000Y-79200D01*
G01X650100Y-80400D02*
X653300D01*
X653000Y-79467D01*
X652500Y-78933D01*
X651800Y-78667D01*
X651100Y-78800D01*
X650500Y-79200D01*
X650100Y-80133D01*
X649900Y-80934D01*
Y-81733D01*
X650100Y-82533D01*
X650600Y-83333D01*
X651200Y-83867D01*
X651900Y-84000D01*
X652600Y-83733D01*
X653300Y-82934D01*
G01X661400Y-84000D02*
Y-78667D01*
G01Y-79600D02*
X661000Y-79067D01*
X660400Y-78800D01*
X659700Y-78667D01*
X659000Y-78933D01*
X658400Y-79467D01*
X658000Y-80267D01*
X657800Y-81333D01*
X658000Y-82400D01*
X658400Y-83200D01*
X659000Y-83733D01*
X659700Y-84000D01*
X660400Y-83867D01*
X661000Y-83467D01*
X661400Y-82934D01*
G01X665900Y-84000D02*
Y-76000D01*
G01X669100Y-78667D02*
X665900Y-81733D01*
G01X667200Y-80533D02*
X669300Y-84000D01*
G01X677400D02*
Y-78667D01*
G01Y-79600D02*
X677000Y-79067D01*
X676400Y-78800D01*
X675700Y-78667D01*
X675000Y-78933D01*
X674400Y-79467D01*
X674000Y-80267D01*
X673800Y-81333D01*
X674000Y-82400D01*
X674400Y-83200D01*
X675000Y-83733D01*
X675700Y-84000D01*
X676400Y-83867D01*
X677000Y-83467D01*
X677400Y-82934D01*
G01X681100Y-78667D02*
X682300Y-84000D01*
X683600Y-78667D01*
X684900Y-84000D01*
X686100Y-78667D01*
G01X693400Y-84000D02*
Y-78667D01*
G01Y-79600D02*
X693000Y-79067D01*
X692400Y-78800D01*
X691700Y-78667D01*
X691000Y-78933D01*
X690400Y-79467D01*
X690000Y-80267D01*
X689800Y-81333D01*
X690000Y-82400D01*
X690400Y-83200D01*
X691000Y-83733D01*
X691700Y-84000D01*
X692400Y-83867D01*
X693000Y-83467D01*
X693400Y-82934D01*
G01X697500Y-86400D02*
X698100Y-86667D01*
X698900Y-86400D01*
X699400Y-85867D01*
X699800Y-85200D01*
X700400Y-83067D01*
X701700Y-78667D01*
G01X698500D02*
X700400Y-83067D01*
G01X708100Y-86667D02*
X709100Y-85333D01*
X709600Y-84000D01*
Y-78667D01*
X709100Y-77333D01*
X708100Y-76000D01*
G01X465300Y-72000D02*
Y-64000D01*
X469900Y-72000D01*
Y-64000D01*
G01X473600Y-72000D02*
Y-64000D01*
X476000D01*
X476800Y-64400D01*
X477400Y-65333D01*
X477600Y-66400D01*
X477400Y-67467D01*
X476900Y-68267D01*
X476000Y-68667D01*
X473600D01*
G01X483600Y-64000D02*
Y-72000D01*
G01X481300Y-64000D02*
X485900D01*
G01X489500Y-72000D02*
Y-64000D01*
G01X493700D02*
Y-72000D01*
G01Y-68000D02*
X489500D01*
G01X505500Y-70934D02*
X506300Y-71600D01*
X507200Y-72000D01*
X508000D01*
X508800Y-71600D01*
X509400Y-70934D01*
X509700Y-70000D01*
X509500Y-69067D01*
X509000Y-68267D01*
X508100Y-67733D01*
X506900Y-67467D01*
X506200Y-66933D01*
X505900Y-66000D01*
X506100Y-65067D01*
X506600Y-64400D01*
X507300Y-64000D01*
X508000D01*
X508700Y-64267D01*
X509300Y-64933D01*
G01X515600Y-66667D02*
Y-72000D01*
G01Y-64533D02*
X515400Y-64400D01*
Y-64133D01*
X515600Y-64000D01*
X515800Y-64133D01*
Y-64400D01*
X515600Y-64533D01*
G01X522100Y-66667D02*
X525100D01*
X522100Y-72000D01*
X525100D01*
G01X530100Y-68400D02*
X533300D01*
X533000Y-67467D01*
X532500Y-66933D01*
X531800Y-66667D01*
X531100Y-66800D01*
X530500Y-67200D01*
X530100Y-68133D01*
X529900Y-68934D01*
Y-69733D01*
X530100Y-70533D01*
X530600Y-71333D01*
X531200Y-71867D01*
X531900Y-72000D01*
X532600Y-71733D01*
X533300Y-70934D01*
G01X545400Y-70400D02*
X546000Y-71333D01*
X546800Y-71867D01*
X547700Y-72000D01*
X548500Y-71867D01*
X549300Y-71200D01*
X549800Y-70400D01*
X549900Y-69600D01*
X549700Y-68667D01*
X549000Y-68000D01*
X548300Y-67733D01*
X547400D01*
G01X548300D02*
X548900Y-67333D01*
X549400Y-66667D01*
X549600Y-65867D01*
X549400Y-65067D01*
X548900Y-64400D01*
X548000Y-64000D01*
X547100Y-64133D01*
X546200Y-64667D01*
G01X555600Y-72267D02*
X555400Y-72133D01*
Y-71867D01*
X555600Y-71733D01*
X555800Y-71867D01*
Y-72133D01*
X555600Y-72267D01*
G01X561400Y-70800D02*
X562000Y-71467D01*
X562700Y-71867D01*
X563600Y-72000D01*
X564500Y-71733D01*
X565200Y-71200D01*
X565700Y-70267D01*
X565800Y-69200D01*
X565600Y-68133D01*
X565100Y-67467D01*
X564400Y-66933D01*
X563700Y-66800D01*
X563000Y-66933D01*
X562100Y-67467D01*
X562400Y-64000D01*
X565100D01*
G01X569400Y-70800D02*
X570000Y-71467D01*
X570700Y-71867D01*
X571600Y-72000D01*
X572500Y-71733D01*
X573200Y-71200D01*
X573700Y-70267D01*
X573800Y-69200D01*
X573600Y-68133D01*
X573100Y-67467D01*
X572400Y-66933D01*
X571700Y-66800D01*
X571000Y-66933D01*
X570100Y-67467D01*
X570400Y-64000D01*
X573100D01*
G01X576600Y-72000D02*
Y-66667D01*
G01Y-68133D02*
X576900Y-67467D01*
X577400Y-66933D01*
X578100Y-66667D01*
X578800Y-66933D01*
X579300Y-67467D01*
X579600Y-68133D01*
Y-72000D01*
G01Y-68133D02*
X579900Y-67467D01*
X580400Y-66933D01*
X581100Y-66667D01*
X581800Y-66933D01*
X582300Y-67467D01*
X582600Y-68267D01*
Y-72000D01*
G01X584600D02*
Y-66667D01*
G01Y-68133D02*
X584900Y-67467D01*
X585400Y-66933D01*
X586100Y-66667D01*
X586800Y-66933D01*
X587300Y-67467D01*
X587600Y-68133D01*
Y-72000D01*
G01Y-68133D02*
X587900Y-67467D01*
X588400Y-66933D01*
X589100Y-66667D01*
X589800Y-66933D01*
X590300Y-67467D01*
X590600Y-68267D01*
Y-72000D01*
G01X603100Y-74667D02*
X602100Y-73333D01*
X601600Y-72000D01*
Y-66667D01*
X602100Y-65333D01*
X603100Y-64000D01*
G01X611600Y-72000D02*
X611000Y-71867D01*
X610400Y-71333D01*
X610000Y-70400D01*
X609800Y-69333D01*
X610000Y-68267D01*
X610400Y-67333D01*
X611000Y-66800D01*
X611600Y-66667D01*
X612200Y-66800D01*
X612800Y-67333D01*
X613200Y-68267D01*
X613300Y-69333D01*
X613200Y-70400D01*
X612800Y-71333D01*
X612200Y-71867D01*
X611600Y-72000D01*
G01X617900D02*
Y-66667D01*
G01Y-68000D02*
X618300Y-67333D01*
X618900Y-66800D01*
X619700Y-66667D01*
X620400Y-66800D01*
X621000Y-67333D01*
X621300Y-68267D01*
Y-72000D01*
G01X633800D02*
Y-64000D01*
G01Y-68000D02*
X634300Y-67200D01*
X634900Y-66800D01*
X635500Y-66667D01*
X636400Y-66933D01*
X637000Y-67467D01*
X637400Y-68400D01*
Y-69467D01*
X637200Y-70533D01*
X636800Y-71333D01*
X636100Y-71867D01*
X635500Y-72000D01*
X634900Y-71867D01*
X634300Y-71467D01*
X633800Y-70800D01*
G01X642200Y-72000D02*
Y-66667D01*
G01Y-67733D02*
X642700Y-67200D01*
X643200Y-66800D01*
X643900Y-66667D01*
X644400Y-66800D01*
X645000Y-67200D01*
G01X650100Y-68400D02*
X653300D01*
X653000Y-67467D01*
X652500Y-66933D01*
X651800Y-66667D01*
X651100Y-66800D01*
X650500Y-67200D01*
X650100Y-68133D01*
X649900Y-68934D01*
Y-69733D01*
X650100Y-70533D01*
X650600Y-71333D01*
X651200Y-71867D01*
X651900Y-72000D01*
X652600Y-71733D01*
X653300Y-70934D01*
G01X661400Y-72000D02*
Y-66667D01*
G01Y-67600D02*
X661000Y-67067D01*
X660400Y-66800D01*
X659700Y-66667D01*
X659000Y-66933D01*
X658400Y-67467D01*
X658000Y-68267D01*
X657800Y-69333D01*
X658000Y-70400D01*
X658400Y-71200D01*
X659000Y-71733D01*
X659700Y-72000D01*
X660400Y-71867D01*
X661000Y-71467D01*
X661400Y-70934D01*
G01X665900Y-72000D02*
Y-64000D01*
G01X669100Y-66667D02*
X665900Y-69733D01*
G01X667200Y-68533D02*
X669300Y-72000D01*
G01X677400D02*
Y-66667D01*
G01Y-67600D02*
X677000Y-67067D01*
X676400Y-66800D01*
X675700Y-66667D01*
X675000Y-66933D01*
X674400Y-67467D01*
X674000Y-68267D01*
X673800Y-69333D01*
X674000Y-70400D01*
X674400Y-71200D01*
X675000Y-71733D01*
X675700Y-72000D01*
X676400Y-71867D01*
X677000Y-71467D01*
X677400Y-70934D01*
G01X681100Y-66667D02*
X682300Y-72000D01*
X683600Y-66667D01*
X684900Y-72000D01*
X686100Y-66667D01*
G01X693400Y-72000D02*
Y-66667D01*
G01Y-67600D02*
X693000Y-67067D01*
X692400Y-66800D01*
X691700Y-66667D01*
X691000Y-66933D01*
X690400Y-67467D01*
X690000Y-68267D01*
X689800Y-69333D01*
X690000Y-70400D01*
X690400Y-71200D01*
X691000Y-71733D01*
X691700Y-72000D01*
X692400Y-71867D01*
X693000Y-71467D01*
X693400Y-70934D01*
G01X697500Y-74400D02*
X698100Y-74667D01*
X698900Y-74400D01*
X699400Y-73867D01*
X699800Y-73200D01*
X700400Y-71067D01*
X701700Y-66667D01*
G01X698500D02*
X700400Y-71067D01*
G01X708100Y-74667D02*
X709100Y-73333D01*
X709600Y-72000D01*
Y-66667D01*
X709100Y-65333D01*
X708100Y-64000D01*
G01X465300Y-58500D02*
Y-50500D01*
X469900Y-58500D01*
Y-50500D01*
G01X473600Y-58500D02*
Y-50500D01*
X476000D01*
X476800Y-50900D01*
X477400Y-51833D01*
X477600Y-52900D01*
X477400Y-53967D01*
X476900Y-54767D01*
X476000Y-55167D01*
X473600D01*
G01X483600Y-50500D02*
Y-58500D01*
G01X481300Y-50500D02*
X485900D01*
G01X489500Y-58500D02*
Y-50500D01*
G01X493700D02*
Y-58500D01*
G01Y-54500D02*
X489500D01*
G01X505500Y-57434D02*
X506300Y-58100D01*
X507200Y-58500D01*
X508000D01*
X508800Y-58100D01*
X509400Y-57434D01*
X509700Y-56500D01*
X509500Y-55567D01*
X509000Y-54767D01*
X508100Y-54233D01*
X506900Y-53967D01*
X506200Y-53433D01*
X505900Y-52500D01*
X506100Y-51567D01*
X506600Y-50900D01*
X507300Y-50500D01*
X508000D01*
X508700Y-50767D01*
X509300Y-51433D01*
G01X515600Y-53167D02*
Y-58500D01*
G01Y-51033D02*
X515400Y-50900D01*
Y-50633D01*
X515600Y-50500D01*
X515800Y-50633D01*
Y-50900D01*
X515600Y-51033D01*
G01X522100Y-53167D02*
X525100D01*
X522100Y-58500D01*
X525100D01*
G01X530100Y-54900D02*
X533300D01*
X533000Y-53967D01*
X532500Y-53433D01*
X531800Y-53167D01*
X531100Y-53300D01*
X530500Y-53700D01*
X530100Y-54633D01*
X529900Y-55434D01*
Y-56233D01*
X530100Y-57033D01*
X530600Y-57833D01*
X531200Y-58367D01*
X531900Y-58500D01*
X532600Y-58233D01*
X533300Y-57434D01*
G01X541600Y-58500D02*
X537600Y-55833D01*
X541600Y-53167D01*
G01X553400Y-57300D02*
X554000Y-57967D01*
X554700Y-58367D01*
X555600Y-58500D01*
X556500Y-58233D01*
X557200Y-57700D01*
X557700Y-56767D01*
X557800Y-55700D01*
X557600Y-54633D01*
X557100Y-53967D01*
X556400Y-53433D01*
X555700Y-53300D01*
X555000Y-53433D01*
X554100Y-53967D01*
X554400Y-50500D01*
X557100D01*
G01X560600Y-58500D02*
Y-53167D01*
G01Y-54633D02*
X560900Y-53967D01*
X561400Y-53433D01*
X562100Y-53167D01*
X562800Y-53433D01*
X563300Y-53967D01*
X563600Y-54633D01*
Y-58500D01*
G01Y-54633D02*
X563900Y-53967D01*
X564400Y-53433D01*
X565100Y-53167D01*
X565800Y-53433D01*
X566300Y-53967D01*
X566600Y-54767D01*
Y-58500D01*
G01X568600D02*
Y-53167D01*
G01Y-54633D02*
X568900Y-53967D01*
X569400Y-53433D01*
X570100Y-53167D01*
X570800Y-53433D01*
X571300Y-53967D01*
X571600Y-54633D01*
Y-58500D01*
G01Y-54633D02*
X571900Y-53967D01*
X572400Y-53433D01*
X573100Y-53167D01*
X573800Y-53433D01*
X574300Y-53967D01*
X574600Y-54767D01*
Y-58500D01*
G01X587100Y-61167D02*
X586100Y-59833D01*
X585600Y-58500D01*
Y-53167D01*
X586100Y-51833D01*
X587100Y-50500D01*
G01X593900Y-58500D02*
Y-53167D01*
G01Y-54500D02*
X594300Y-53833D01*
X594900Y-53300D01*
X595700Y-53167D01*
X596400Y-53300D01*
X597000Y-53833D01*
X597300Y-54767D01*
Y-58500D01*
G01X603600D02*
X603000Y-58367D01*
X602400Y-57833D01*
X602000Y-56900D01*
X601800Y-55833D01*
X602000Y-54767D01*
X602400Y-53833D01*
X603000Y-53300D01*
X603600Y-53167D01*
X604200Y-53300D01*
X604800Y-53833D01*
X605200Y-54767D01*
X605300Y-55833D01*
X605200Y-56900D01*
X604800Y-57833D01*
X604200Y-58367D01*
X603600Y-58500D01*
G01X611600Y-50500D02*
Y-58500D01*
G01X610200Y-53167D02*
X613000D01*
G01X627600Y-58500D02*
X627000Y-58367D01*
X626400Y-57833D01*
X626000Y-56900D01*
X625800Y-55833D01*
X626000Y-54767D01*
X626400Y-53833D01*
X627000Y-53300D01*
X627600Y-53167D01*
X628200Y-53300D01*
X628800Y-53833D01*
X629200Y-54767D01*
X629300Y-55833D01*
X629200Y-56900D01*
X628800Y-57833D01*
X628200Y-58367D01*
X627600Y-58500D01*
G01X633900D02*
Y-53167D01*
G01Y-54500D02*
X634300Y-53833D01*
X634900Y-53300D01*
X635700Y-53167D01*
X636400Y-53300D01*
X637000Y-53833D01*
X637300Y-54767D01*
Y-58500D01*
G01X649800D02*
Y-50500D01*
G01Y-54500D02*
X650300Y-53700D01*
X650900Y-53300D01*
X651500Y-53167D01*
X652400Y-53433D01*
X653000Y-53967D01*
X653400Y-54900D01*
Y-55967D01*
X653200Y-57033D01*
X652800Y-57833D01*
X652100Y-58367D01*
X651500Y-58500D01*
X650900Y-58367D01*
X650300Y-57967D01*
X649800Y-57300D01*
G01X658200Y-58500D02*
Y-53167D01*
G01Y-54233D02*
X658700Y-53700D01*
X659200Y-53300D01*
X659900Y-53167D01*
X660400Y-53300D01*
X661000Y-53700D01*
G01X666100Y-54900D02*
X669300D01*
X669000Y-53967D01*
X668500Y-53433D01*
X667800Y-53167D01*
X667100Y-53300D01*
X666500Y-53700D01*
X666100Y-54633D01*
X665900Y-55434D01*
Y-56233D01*
X666100Y-57033D01*
X666600Y-57833D01*
X667200Y-58367D01*
X667900Y-58500D01*
X668600Y-58233D01*
X669300Y-57434D01*
G01X677400Y-58500D02*
Y-53167D01*
G01Y-54100D02*
X677000Y-53567D01*
X676400Y-53300D01*
X675700Y-53167D01*
X675000Y-53433D01*
X674400Y-53967D01*
X674000Y-54767D01*
X673800Y-55833D01*
X674000Y-56900D01*
X674400Y-57700D01*
X675000Y-58233D01*
X675700Y-58500D01*
X676400Y-58367D01*
X677000Y-57967D01*
X677400Y-57434D01*
G01X681900Y-58500D02*
Y-50500D01*
G01X685100Y-53167D02*
X681900Y-56233D01*
G01X683200Y-55033D02*
X685300Y-58500D01*
G01X693400D02*
Y-53167D01*
G01Y-54100D02*
X693000Y-53567D01*
X692400Y-53300D01*
X691700Y-53167D01*
X691000Y-53433D01*
X690400Y-53967D01*
X690000Y-54767D01*
X689800Y-55833D01*
X690000Y-56900D01*
X690400Y-57700D01*
X691000Y-58233D01*
X691700Y-58500D01*
X692400Y-58367D01*
X693000Y-57967D01*
X693400Y-57434D01*
G01X697100Y-53167D02*
X698300Y-58500D01*
X699600Y-53167D01*
X700900Y-58500D01*
X702100Y-53167D01*
G01X709400Y-58500D02*
Y-53167D01*
G01Y-54100D02*
X709000Y-53567D01*
X708400Y-53300D01*
X707700Y-53167D01*
X707000Y-53433D01*
X706400Y-53967D01*
X706000Y-54767D01*
X705800Y-55833D01*
X706000Y-56900D01*
X706400Y-57700D01*
X707000Y-58233D01*
X707700Y-58500D01*
X708400Y-58367D01*
X709000Y-57967D01*
X709400Y-57434D01*
G01X713500Y-60900D02*
X714100Y-61167D01*
X714900Y-60900D01*
X715400Y-60367D01*
X715800Y-59700D01*
X716400Y-57567D01*
X717700Y-53167D01*
G01X714500D02*
X716400Y-57567D01*
G01X724100Y-61167D02*
X725100Y-59833D01*
X725600Y-58500D01*
Y-53167D01*
X725100Y-51833D01*
X724100Y-50500D01*
G01X464900Y-38000D02*
Y-43733D01*
X465300Y-44934D01*
X466100Y-45733D01*
X467100Y-46000D01*
X468100Y-45733D01*
X468900Y-44934D01*
X469300Y-43733D01*
Y-38000D01*
G01X473400Y-46000D02*
Y-40667D01*
G01Y-42000D02*
X473800Y-41333D01*
X474400Y-40800D01*
X475200Y-40667D01*
X475900Y-40800D01*
X476500Y-41333D01*
X476800Y-42267D01*
Y-46000D01*
G01X481800Y-43333D02*
X484400D01*
G01X489300Y-48667D02*
Y-40667D01*
G01Y-41867D02*
X489800Y-41200D01*
X490300Y-40800D01*
X491100Y-40667D01*
X491800Y-40800D01*
X492500Y-41467D01*
X492800Y-42400D01*
X492900Y-43333D01*
X492800Y-44267D01*
X492500Y-45200D01*
X491900Y-45733D01*
X491100Y-46000D01*
X490400Y-45867D01*
X489700Y-45467D01*
X489300Y-44934D01*
G01X499100Y-46000D02*
Y-38000D01*
G01X505400Y-40667D02*
Y-44400D01*
X505800Y-45333D01*
X506400Y-45867D01*
X507100Y-46000D01*
X507800Y-45867D01*
X508400Y-45333D01*
X508800Y-44400D01*
G01Y-46000D02*
Y-40667D01*
G01X513700Y-48000D02*
X514400Y-48533D01*
X515200Y-48667D01*
X515900Y-48533D01*
X516500Y-47867D01*
X516900Y-46933D01*
Y-40667D01*
G01Y-41733D02*
X516500Y-41200D01*
X515900Y-40800D01*
X515200Y-40667D01*
X514400Y-40933D01*
X513900Y-41467D01*
X513500Y-42400D01*
X513300Y-43333D01*
X513400Y-44133D01*
X513800Y-45067D01*
X514400Y-45733D01*
X515200Y-46000D01*
X515800Y-45867D01*
X516500Y-45333D01*
X516900Y-44800D01*
G01X521700Y-48000D02*
X522400Y-48533D01*
X523200Y-48667D01*
X523900Y-48533D01*
X524500Y-47867D01*
X524900Y-46933D01*
Y-40667D01*
G01Y-41733D02*
X524500Y-41200D01*
X523900Y-40800D01*
X523200Y-40667D01*
X522400Y-40933D01*
X521900Y-41467D01*
X521500Y-42400D01*
X521300Y-43333D01*
X521400Y-44133D01*
X521800Y-45067D01*
X522400Y-45733D01*
X523200Y-46000D01*
X523800Y-45867D01*
X524500Y-45333D01*
X524900Y-44800D01*
G01X529600Y-42400D02*
X532800D01*
X532500Y-41467D01*
X532000Y-40933D01*
X531300Y-40667D01*
X530600Y-40800D01*
X530000Y-41200D01*
X529600Y-42133D01*
X529400Y-42934D01*
Y-43733D01*
X529600Y-44533D01*
X530100Y-45333D01*
X530700Y-45867D01*
X531400Y-46000D01*
X532100Y-45733D01*
X532800Y-44934D01*
G01X540900Y-38000D02*
Y-46000D01*
G01Y-44800D02*
X540500Y-45467D01*
X539900Y-45867D01*
X539200Y-46000D01*
X538400Y-45733D01*
X537800Y-45067D01*
X537400Y-44267D01*
X537300Y-43333D01*
X537400Y-42400D01*
X537800Y-41600D01*
X538400Y-40933D01*
X539200Y-40667D01*
X539900Y-40800D01*
X540400Y-41067D01*
X540900Y-41600D01*
G01X553100Y-46000D02*
Y-38000D01*
X555500D01*
X556300Y-38400D01*
X556900Y-39333D01*
X557100Y-40400D01*
X556900Y-41467D01*
X556400Y-42267D01*
X555500Y-42667D01*
X553100D01*
G01X563100Y-38000D02*
Y-46000D01*
G01X560800Y-38000D02*
X565400D01*
G01X569000Y-46000D02*
Y-38000D01*
G01X573200D02*
Y-46000D01*
G01Y-42000D02*
X569000D01*
G01X586600Y-48667D02*
X585600Y-47333D01*
X585100Y-46000D01*
Y-40667D01*
X585600Y-39333D01*
X586600Y-38000D01*
G01X593000Y-46000D02*
Y-38000D01*
G01X597200D02*
Y-46000D01*
G01Y-42000D02*
X593000D01*
G01X603100Y-46000D02*
X602500Y-45867D01*
X601900Y-45333D01*
X601500Y-44400D01*
X601300Y-43333D01*
X601500Y-42267D01*
X601900Y-41333D01*
X602500Y-40800D01*
X603100Y-40667D01*
X603700Y-40800D01*
X604300Y-41333D01*
X604700Y-42267D01*
X604800Y-43333D01*
X604700Y-44400D01*
X604300Y-45333D01*
X603700Y-45867D01*
X603100Y-46000D01*
G01X611100D02*
Y-38000D01*
G01X617600Y-42400D02*
X620800D01*
X620500Y-41467D01*
X620000Y-40933D01*
X619300Y-40667D01*
X618600Y-40800D01*
X618000Y-41200D01*
X617600Y-42133D01*
X617400Y-42934D01*
Y-43733D01*
X617600Y-44533D01*
X618100Y-45333D01*
X618700Y-45867D01*
X619400Y-46000D01*
X620100Y-45733D01*
X620800Y-44934D01*
G01X633000D02*
X633800Y-45600D01*
X634700Y-46000D01*
X635500D01*
X636300Y-45600D01*
X636900Y-44934D01*
X637200Y-44000D01*
X637000Y-43067D01*
X636500Y-42267D01*
X635600Y-41733D01*
X634400Y-41467D01*
X633700Y-40933D01*
X633400Y-40000D01*
X633600Y-39067D01*
X634100Y-38400D01*
X634800Y-38000D01*
X635500D01*
X636200Y-38267D01*
X636800Y-38933D01*
G01X643100Y-40667D02*
Y-46000D01*
G01Y-38533D02*
X642900Y-38400D01*
Y-38133D01*
X643100Y-38000D01*
X643300Y-38133D01*
Y-38400D01*
X643100Y-38533D01*
G01X649600Y-40667D02*
X652600D01*
X649600Y-46000D01*
X652600D01*
G01X657600Y-42400D02*
X660800D01*
X660500Y-41467D01*
X660000Y-40933D01*
X659300Y-40667D01*
X658600Y-40800D01*
X658000Y-41200D01*
X657600Y-42133D01*
X657400Y-42934D01*
Y-43733D01*
X657600Y-44533D01*
X658100Y-45333D01*
X658700Y-45867D01*
X659400Y-46000D01*
X660100Y-45733D01*
X660800Y-44934D01*
G01X669100Y-46000D02*
X665100Y-43333D01*
X669100Y-40667D01*
G01X675100Y-46000D02*
Y-38000D01*
X673900Y-39600D01*
G01Y-46000D02*
X676300D01*
G01X681400Y-45067D02*
X682100Y-45733D01*
X682900Y-46000D01*
X683700Y-45733D01*
X684400Y-44934D01*
X684900Y-43733D01*
X685100Y-42533D01*
Y-41067D01*
X684900Y-39867D01*
X684400Y-38800D01*
X683800Y-38267D01*
X683100Y-38000D01*
X682300Y-38267D01*
X681700Y-38800D01*
X681300Y-39600D01*
X681100Y-40667D01*
X681300Y-41600D01*
X681800Y-42533D01*
X682400Y-43067D01*
X683100Y-43200D01*
X683900Y-42934D01*
X684500Y-42267D01*
X685100Y-41067D01*
G01X690900Y-46000D02*
X691100Y-44267D01*
X691400Y-42800D01*
X691800Y-41467D01*
X692300Y-40000D01*
X693100Y-38000D01*
X689100D01*
G01X696100Y-46000D02*
Y-40667D01*
G01Y-42133D02*
X696400Y-41467D01*
X696900Y-40933D01*
X697600Y-40667D01*
X698300Y-40933D01*
X698800Y-41467D01*
X699100Y-42133D01*
Y-46000D01*
G01Y-42133D02*
X699400Y-41467D01*
X699900Y-40933D01*
X700600Y-40667D01*
X701300Y-40933D01*
X701800Y-41467D01*
X702100Y-42267D01*
Y-46000D01*
G01X707100Y-40667D02*
Y-46000D01*
G01Y-38533D02*
X706900Y-38400D01*
Y-38133D01*
X707100Y-38000D01*
X707300Y-38133D01*
Y-38400D01*
X707100Y-38533D01*
G01X715100Y-46000D02*
Y-38000D01*
G01X728600Y-40667D02*
X729800Y-46000D01*
X731100Y-40667D01*
X732400Y-46000D01*
X733600Y-40667D01*
G01X739100D02*
Y-46000D01*
G01Y-38533D02*
X738900Y-38400D01*
Y-38133D01*
X739100Y-38000D01*
X739300Y-38133D01*
Y-38400D01*
X739100Y-38533D01*
G01X747100Y-38000D02*
Y-46000D01*
G01X745700Y-40667D02*
X748500D01*
G01X753400Y-46000D02*
Y-38000D01*
G01Y-41867D02*
X753900Y-41200D01*
X754400Y-40800D01*
X755200Y-40667D01*
X755800Y-40800D01*
X756500Y-41333D01*
X756800Y-42133D01*
Y-46000D01*
G01X769000D02*
Y-38000D01*
G01X773200D02*
Y-46000D01*
G01Y-42000D02*
X769000D01*
G01X776600Y-46000D02*
X779100Y-38000D01*
X781600Y-46000D01*
G01X780700Y-43200D02*
X777500D01*
G01X785000Y-44934D02*
X785800Y-45600D01*
X786700Y-46000D01*
X787500D01*
X788300Y-45600D01*
X788900Y-44934D01*
X789200Y-44000D01*
X789000Y-43067D01*
X788500Y-42267D01*
X787600Y-41733D01*
X786400Y-41467D01*
X785700Y-40933D01*
X785400Y-40000D01*
X785600Y-39067D01*
X786100Y-38400D01*
X786800Y-38000D01*
X787500D01*
X788200Y-38267D01*
X788800Y-38933D01*
G01X793100Y-38000D02*
Y-46000D01*
X797100D01*
G01X809300Y-48667D02*
Y-40667D01*
G01Y-41867D02*
X809800Y-41200D01*
X810300Y-40800D01*
X811100Y-40667D01*
X811800Y-40800D01*
X812500Y-41467D01*
X812800Y-42400D01*
X812900Y-43333D01*
X812800Y-44267D01*
X812500Y-45200D01*
X811900Y-45733D01*
X811100Y-46000D01*
X810400Y-45867D01*
X809700Y-45467D01*
X809300Y-44934D01*
G01X817700Y-46000D02*
Y-40667D01*
G01Y-41733D02*
X818200Y-41200D01*
X818700Y-40800D01*
X819400Y-40667D01*
X819900Y-40800D01*
X820500Y-41200D01*
G01X827100Y-46000D02*
X826500Y-45867D01*
X825900Y-45333D01*
X825500Y-44400D01*
X825300Y-43333D01*
X825500Y-42267D01*
X825900Y-41333D01*
X826500Y-40800D01*
X827100Y-40667D01*
X827700Y-40800D01*
X828300Y-41333D01*
X828700Y-42267D01*
X828800Y-43333D01*
X828700Y-44400D01*
X828300Y-45333D01*
X827700Y-45867D01*
X827100Y-46000D01*
G01X836900Y-38000D02*
Y-46000D01*
G01Y-44800D02*
X836500Y-45467D01*
X835900Y-45867D01*
X835200Y-46000D01*
X834400Y-45733D01*
X833800Y-45067D01*
X833400Y-44267D01*
X833300Y-43333D01*
X833400Y-42400D01*
X833800Y-41600D01*
X834400Y-40933D01*
X835200Y-40667D01*
X835900Y-40800D01*
X836400Y-41067D01*
X836900Y-41600D01*
G01X841400Y-40667D02*
Y-44400D01*
X841800Y-45333D01*
X842400Y-45867D01*
X843100Y-46000D01*
X843800Y-45867D01*
X844400Y-45333D01*
X844800Y-44400D01*
G01Y-46000D02*
Y-40667D01*
G01X852700Y-41333D02*
X852000Y-40800D01*
X851400Y-40667D01*
X850600Y-40933D01*
X850000Y-41467D01*
X849600Y-42400D01*
X849500Y-43333D01*
X849600Y-44267D01*
X850000Y-45067D01*
X850600Y-45733D01*
X851400Y-46000D01*
X852100Y-45733D01*
X852700Y-45200D01*
G01X859100Y-38000D02*
Y-46000D01*
G01X857700Y-40667D02*
X860500D01*
G01X865600Y-45067D02*
X866100Y-45600D01*
X866800Y-46000D01*
X867400D01*
X868000Y-45733D01*
X868400Y-45333D01*
X868600Y-44800D01*
X868500Y-44000D01*
X868100Y-43600D01*
X866300Y-42800D01*
X865900Y-41867D01*
X866100Y-41200D01*
X866500Y-40800D01*
X867100Y-40667D01*
X867700Y-40800D01*
X868300Y-41200D01*
G01X875600Y-48667D02*
X876600Y-47333D01*
X877100Y-46000D01*
Y-40667D01*
X876600Y-39333D01*
X875600Y-38000D01*
G01X464900Y-25500D02*
Y-31233D01*
X465300Y-32434D01*
X466100Y-33233D01*
X467100Y-33500D01*
X468100Y-33233D01*
X468900Y-32434D01*
X469300Y-31233D01*
Y-25500D01*
G01X473400Y-33500D02*
Y-28167D01*
G01Y-29500D02*
X473800Y-28833D01*
X474400Y-28300D01*
X475200Y-28167D01*
X475900Y-28300D01*
X476500Y-28833D01*
X476800Y-29767D01*
Y-33500D01*
G01X481800Y-30833D02*
X484400D01*
G01X489300Y-36167D02*
Y-28167D01*
G01Y-29367D02*
X489800Y-28700D01*
X490300Y-28300D01*
X491100Y-28167D01*
X491800Y-28300D01*
X492500Y-28967D01*
X492800Y-29900D01*
X492900Y-30833D01*
X492800Y-31767D01*
X492500Y-32700D01*
X491900Y-33233D01*
X491100Y-33500D01*
X490400Y-33367D01*
X489700Y-32967D01*
X489300Y-32434D01*
G01X499100Y-33500D02*
Y-25500D01*
G01X505400Y-28167D02*
Y-31900D01*
X505800Y-32833D01*
X506400Y-33367D01*
X507100Y-33500D01*
X507800Y-33367D01*
X508400Y-32833D01*
X508800Y-31900D01*
G01Y-33500D02*
Y-28167D01*
G01X513700Y-35500D02*
X514400Y-36033D01*
X515200Y-36167D01*
X515900Y-36033D01*
X516500Y-35367D01*
X516900Y-34433D01*
Y-28167D01*
G01Y-29233D02*
X516500Y-28700D01*
X515900Y-28300D01*
X515200Y-28167D01*
X514400Y-28433D01*
X513900Y-28967D01*
X513500Y-29900D01*
X513300Y-30833D01*
X513400Y-31633D01*
X513800Y-32567D01*
X514400Y-33233D01*
X515200Y-33500D01*
X515800Y-33367D01*
X516500Y-32833D01*
X516900Y-32300D01*
G01X521700Y-35500D02*
X522400Y-36033D01*
X523200Y-36167D01*
X523900Y-36033D01*
X524500Y-35367D01*
X524900Y-34433D01*
Y-28167D01*
G01Y-29233D02*
X524500Y-28700D01*
X523900Y-28300D01*
X523200Y-28167D01*
X522400Y-28433D01*
X521900Y-28967D01*
X521500Y-29900D01*
X521300Y-30833D01*
X521400Y-31633D01*
X521800Y-32567D01*
X522400Y-33233D01*
X523200Y-33500D01*
X523800Y-33367D01*
X524500Y-32833D01*
X524900Y-32300D01*
G01X529600Y-29900D02*
X532800D01*
X532500Y-28967D01*
X532000Y-28433D01*
X531300Y-28167D01*
X530600Y-28300D01*
X530000Y-28700D01*
X529600Y-29633D01*
X529400Y-30434D01*
Y-31233D01*
X529600Y-32033D01*
X530100Y-32833D01*
X530700Y-33367D01*
X531400Y-33500D01*
X532100Y-33233D01*
X532800Y-32434D01*
G01X540900Y-25500D02*
Y-33500D01*
G01Y-32300D02*
X540500Y-32967D01*
X539900Y-33367D01*
X539200Y-33500D01*
X538400Y-33233D01*
X537800Y-32567D01*
X537400Y-31767D01*
X537300Y-30833D01*
X537400Y-29900D01*
X537800Y-29100D01*
X538400Y-28433D01*
X539200Y-28167D01*
X539900Y-28300D01*
X540400Y-28567D01*
X540900Y-29100D01*
G01X553100Y-33500D02*
Y-25500D01*
X555500D01*
X556300Y-25900D01*
X556900Y-26833D01*
X557100Y-27900D01*
X556900Y-28967D01*
X556400Y-29767D01*
X555500Y-30167D01*
X553100D01*
G01X563100Y-25500D02*
Y-33500D01*
G01X560800Y-25500D02*
X565400D01*
G01X569000Y-33500D02*
Y-25500D01*
G01X573200D02*
Y-33500D01*
G01Y-29500D02*
X569000D01*
G01X586600Y-36167D02*
X585600Y-34833D01*
X585100Y-33500D01*
Y-28167D01*
X585600Y-26833D01*
X586600Y-25500D01*
G01X593000Y-33500D02*
Y-25500D01*
G01X597200D02*
Y-33500D01*
G01Y-29500D02*
X593000D01*
G01X603100Y-33500D02*
X602500Y-33367D01*
X601900Y-32833D01*
X601500Y-31900D01*
X601300Y-30833D01*
X601500Y-29767D01*
X601900Y-28833D01*
X602500Y-28300D01*
X603100Y-28167D01*
X603700Y-28300D01*
X604300Y-28833D01*
X604700Y-29767D01*
X604800Y-30833D01*
X604700Y-31900D01*
X604300Y-32833D01*
X603700Y-33367D01*
X603100Y-33500D01*
G01X611100D02*
Y-25500D01*
G01X617600Y-29900D02*
X620800D01*
X620500Y-28967D01*
X620000Y-28433D01*
X619300Y-28167D01*
X618600Y-28300D01*
X618000Y-28700D01*
X617600Y-29633D01*
X617400Y-30434D01*
Y-31233D01*
X617600Y-32033D01*
X618100Y-32833D01*
X618700Y-33367D01*
X619400Y-33500D01*
X620100Y-33233D01*
X620800Y-32434D01*
G01X633000D02*
X633800Y-33100D01*
X634700Y-33500D01*
X635500D01*
X636300Y-33100D01*
X636900Y-32434D01*
X637200Y-31500D01*
X637000Y-30567D01*
X636500Y-29767D01*
X635600Y-29233D01*
X634400Y-28967D01*
X633700Y-28433D01*
X633400Y-27500D01*
X633600Y-26567D01*
X634100Y-25900D01*
X634800Y-25500D01*
X635500D01*
X636200Y-25767D01*
X636800Y-26433D01*
G01X643100Y-28167D02*
Y-33500D01*
G01Y-26033D02*
X642900Y-25900D01*
Y-25633D01*
X643100Y-25500D01*
X643300Y-25633D01*
Y-25900D01*
X643100Y-26033D01*
G01X649600Y-28167D02*
X652600D01*
X649600Y-33500D01*
X652600D01*
G01X657600Y-29900D02*
X660800D01*
X660500Y-28967D01*
X660000Y-28433D01*
X659300Y-28167D01*
X658600Y-28300D01*
X658000Y-28700D01*
X657600Y-29633D01*
X657400Y-30434D01*
Y-31233D01*
X657600Y-32033D01*
X658100Y-32833D01*
X658700Y-33367D01*
X659400Y-33500D01*
X660100Y-33233D01*
X660800Y-32434D01*
G01X669100Y-33500D02*
X665100Y-30833D01*
X669100Y-28167D01*
G01X675100Y-33500D02*
Y-25500D01*
X673900Y-27100D01*
G01Y-33500D02*
X676300D01*
G01X681400Y-32567D02*
X682100Y-33233D01*
X682900Y-33500D01*
X683700Y-33233D01*
X684400Y-32434D01*
X684900Y-31233D01*
X685100Y-30033D01*
Y-28567D01*
X684900Y-27367D01*
X684400Y-26300D01*
X683800Y-25767D01*
X683100Y-25500D01*
X682300Y-25767D01*
X681700Y-26300D01*
X681300Y-27100D01*
X681100Y-28167D01*
X681300Y-29100D01*
X681800Y-30033D01*
X682400Y-30567D01*
X683100Y-30700D01*
X683900Y-30434D01*
X684500Y-29767D01*
X685100Y-28567D01*
G01X690900Y-33500D02*
X691100Y-31767D01*
X691400Y-30300D01*
X691800Y-28967D01*
X692300Y-27500D01*
X693100Y-25500D01*
X689100D01*
G01X696100Y-33500D02*
Y-28167D01*
G01Y-29633D02*
X696400Y-28967D01*
X696900Y-28433D01*
X697600Y-28167D01*
X698300Y-28433D01*
X698800Y-28967D01*
X699100Y-29633D01*
Y-33500D01*
G01Y-29633D02*
X699400Y-28967D01*
X699900Y-28433D01*
X700600Y-28167D01*
X701300Y-28433D01*
X701800Y-28967D01*
X702100Y-29767D01*
Y-33500D01*
G01X707100Y-28167D02*
Y-33500D01*
G01Y-26033D02*
X706900Y-25900D01*
Y-25633D01*
X707100Y-25500D01*
X707300Y-25633D01*
Y-25900D01*
X707100Y-26033D01*
G01X715100Y-33500D02*
Y-25500D01*
G01X728600Y-28167D02*
X729800Y-33500D01*
X731100Y-28167D01*
X732400Y-33500D01*
X733600Y-28167D01*
G01X739100D02*
Y-33500D01*
G01Y-26033D02*
X738900Y-25900D01*
Y-25633D01*
X739100Y-25500D01*
X739300Y-25633D01*
Y-25900D01*
X739100Y-26033D01*
G01X747100Y-25500D02*
Y-33500D01*
G01X745700Y-28167D02*
X748500D01*
G01X753400Y-33500D02*
Y-25500D01*
G01Y-29367D02*
X753900Y-28700D01*
X754400Y-28300D01*
X755200Y-28167D01*
X755800Y-28300D01*
X756500Y-28833D01*
X756800Y-29633D01*
Y-33500D01*
G01X769400D02*
Y-28167D01*
G01Y-29500D02*
X769800Y-28833D01*
X770400Y-28300D01*
X771200Y-28167D01*
X771900Y-28300D01*
X772500Y-28833D01*
X772800Y-29767D01*
Y-33500D01*
G01X779100D02*
X778500Y-33367D01*
X777900Y-32833D01*
X777500Y-31900D01*
X777300Y-30833D01*
X777500Y-29767D01*
X777900Y-28833D01*
X778500Y-28300D01*
X779100Y-28167D01*
X779700Y-28300D01*
X780300Y-28833D01*
X780700Y-29767D01*
X780800Y-30833D01*
X780700Y-31900D01*
X780300Y-32833D01*
X779700Y-33367D01*
X779100Y-33500D01*
G01X785400D02*
Y-28167D01*
G01Y-29500D02*
X785800Y-28833D01*
X786400Y-28300D01*
X787200Y-28167D01*
X787900Y-28300D01*
X788500Y-28833D01*
X788800Y-29767D01*
Y-33500D01*
G01X793800Y-30833D02*
X796400D01*
G01X801000Y-33500D02*
Y-25500D01*
G01X805200D02*
Y-33500D01*
G01Y-29500D02*
X801000D01*
G01X808600Y-33500D02*
X811100Y-25500D01*
X813600Y-33500D01*
G01X812700Y-30700D02*
X809500D01*
G01X817000Y-32434D02*
X817800Y-33100D01*
X818700Y-33500D01*
X819500D01*
X820300Y-33100D01*
X820900Y-32434D01*
X821200Y-31500D01*
X821000Y-30567D01*
X820500Y-29767D01*
X819600Y-29233D01*
X818400Y-28967D01*
X817700Y-28433D01*
X817400Y-27500D01*
X817600Y-26567D01*
X818100Y-25900D01*
X818800Y-25500D01*
X819500D01*
X820200Y-25767D01*
X820800Y-26433D01*
G01X825100Y-25500D02*
Y-33500D01*
X829100D01*
G01X841300Y-36167D02*
Y-28167D01*
G01Y-29367D02*
X841800Y-28700D01*
X842300Y-28300D01*
X843100Y-28167D01*
X843800Y-28300D01*
X844500Y-28967D01*
X844800Y-29900D01*
X844900Y-30833D01*
X844800Y-31767D01*
X844500Y-32700D01*
X843900Y-33233D01*
X843100Y-33500D01*
X842400Y-33367D01*
X841700Y-32967D01*
X841300Y-32434D01*
G01X849700Y-33500D02*
Y-28167D01*
G01Y-29233D02*
X850200Y-28700D01*
X850700Y-28300D01*
X851400Y-28167D01*
X851900Y-28300D01*
X852500Y-28700D01*
G01X859100Y-33500D02*
X858500Y-33367D01*
X857900Y-32833D01*
X857500Y-31900D01*
X857300Y-30833D01*
X857500Y-29767D01*
X857900Y-28833D01*
X858500Y-28300D01*
X859100Y-28167D01*
X859700Y-28300D01*
X860300Y-28833D01*
X860700Y-29767D01*
X860800Y-30833D01*
X860700Y-31900D01*
X860300Y-32833D01*
X859700Y-33367D01*
X859100Y-33500D01*
G01X868900Y-25500D02*
Y-33500D01*
G01Y-32300D02*
X868500Y-32967D01*
X867900Y-33367D01*
X867200Y-33500D01*
X866400Y-33233D01*
X865800Y-32567D01*
X865400Y-31767D01*
X865300Y-30833D01*
X865400Y-29900D01*
X865800Y-29100D01*
X866400Y-28433D01*
X867200Y-28167D01*
X867900Y-28300D01*
X868400Y-28567D01*
X868900Y-29100D01*
G01X873400Y-28167D02*
Y-31900D01*
X873800Y-32833D01*
X874400Y-33367D01*
X875100Y-33500D01*
X875800Y-33367D01*
X876400Y-32833D01*
X876800Y-31900D01*
G01Y-33500D02*
Y-28167D01*
G01X884700Y-28833D02*
X884000Y-28300D01*
X883400Y-28167D01*
X882600Y-28433D01*
X882000Y-28967D01*
X881600Y-29900D01*
X881500Y-30833D01*
X881600Y-31767D01*
X882000Y-32567D01*
X882600Y-33233D01*
X883400Y-33500D01*
X884100Y-33233D01*
X884700Y-32700D01*
G01X891100Y-25500D02*
Y-33500D01*
G01X889700Y-28167D02*
X892500D01*
G01X897600Y-32567D02*
X898100Y-33100D01*
X898800Y-33500D01*
X899400D01*
X900000Y-33233D01*
X900400Y-32833D01*
X900600Y-32300D01*
X900500Y-31500D01*
X900100Y-31100D01*
X898300Y-30300D01*
X897900Y-29367D01*
X898100Y-28700D01*
X898500Y-28300D01*
X899100Y-28167D01*
X899700Y-28300D01*
X900300Y-28700D01*
G01X907600Y-36167D02*
X908600Y-34833D01*
X909100Y-33500D01*
Y-28167D01*
X908600Y-26833D01*
X907600Y-25500D01*
G01X479100Y24500D02*
Y16500D01*
G01X477700Y21833D02*
X480500D01*
G01X485400Y16500D02*
Y24500D01*
G01Y20633D02*
X485900Y21300D01*
X486400Y21700D01*
X487200Y21833D01*
X487800Y21700D01*
X488500Y21167D01*
X488800Y20367D01*
Y16500D01*
G01X493600Y20100D02*
X496800D01*
X496500Y21033D01*
X496000Y21567D01*
X495300Y21833D01*
X494600Y21700D01*
X494000Y21300D01*
X493600Y20367D01*
X493400Y19566D01*
Y18767D01*
X493600Y17967D01*
X494100Y17167D01*
X494700Y16633D01*
X495400Y16500D01*
X496100Y16767D01*
X496800Y17566D01*
G01X509700Y16500D02*
Y21833D01*
G01Y20767D02*
X510200Y21300D01*
X510700Y21700D01*
X511400Y21833D01*
X511900Y21700D01*
X512500Y21300D01*
G01X517600Y20100D02*
X520800D01*
X520500Y21033D01*
X520000Y21567D01*
X519300Y21833D01*
X518600Y21700D01*
X518000Y21300D01*
X517600Y20367D01*
X517400Y19566D01*
Y18767D01*
X517600Y17967D01*
X518100Y17167D01*
X518700Y16633D01*
X519400Y16500D01*
X520100Y16767D01*
X520800Y17566D01*
G01X527100Y16500D02*
Y24500D01*
G01X536900Y16500D02*
Y21833D01*
G01Y20900D02*
X536500Y21433D01*
X535900Y21700D01*
X535200Y21833D01*
X534500Y21567D01*
X533900Y21033D01*
X533500Y20233D01*
X533300Y19167D01*
X533500Y18100D01*
X533900Y17300D01*
X534500Y16767D01*
X535200Y16500D01*
X535900Y16633D01*
X536500Y17033D01*
X536900Y17566D01*
G01X543100Y24500D02*
Y16500D01*
G01X541700Y21833D02*
X544500D01*
G01X551100D02*
Y16500D01*
G01Y23967D02*
X550900Y24100D01*
Y24367D01*
X551100Y24500D01*
X551300Y24367D01*
Y24100D01*
X551100Y23967D01*
G01X557300Y21833D02*
X559100Y16500D01*
X560900Y21833D01*
G01X565600Y20100D02*
X568800D01*
X568500Y21033D01*
X568000Y21567D01*
X567300Y21833D01*
X566600Y21700D01*
X566000Y21300D01*
X565600Y20367D01*
X565400Y19566D01*
Y18767D01*
X565600Y17967D01*
X566100Y17167D01*
X566700Y16633D01*
X567400Y16500D01*
X568100Y16767D01*
X568800Y17566D01*
G01X583100Y16500D02*
Y24500D01*
G01X591100Y16500D02*
X590500Y16633D01*
X589900Y17167D01*
X589500Y18100D01*
X589300Y19167D01*
X589500Y20233D01*
X589900Y21167D01*
X590500Y21700D01*
X591100Y21833D01*
X591700Y21700D01*
X592300Y21167D01*
X592700Y20233D01*
X592800Y19167D01*
X592700Y18100D01*
X592300Y17167D01*
X591700Y16633D01*
X591100Y16500D01*
G01X600700Y21167D02*
X600000Y21700D01*
X599400Y21833D01*
X598600Y21567D01*
X598000Y21033D01*
X597600Y20100D01*
X597500Y19167D01*
X597600Y18233D01*
X598000Y17433D01*
X598600Y16767D01*
X599400Y16500D01*
X600100Y16767D01*
X600700Y17300D01*
G01X608900Y16500D02*
Y21833D01*
G01Y20900D02*
X608500Y21433D01*
X607900Y21700D01*
X607200Y21833D01*
X606500Y21567D01*
X605900Y21033D01*
X605500Y20233D01*
X605300Y19167D01*
X605500Y18100D01*
X605900Y17300D01*
X606500Y16767D01*
X607200Y16500D01*
X607900Y16633D01*
X608500Y17033D01*
X608900Y17566D01*
G01X615100Y24500D02*
Y16500D01*
G01X613700Y21833D02*
X616500D01*
G01X623100D02*
Y16500D01*
G01Y23967D02*
X622900Y24100D01*
Y24367D01*
X623100Y24500D01*
X623300Y24367D01*
Y24100D01*
X623100Y23967D01*
G01X631100Y16500D02*
X630500Y16633D01*
X629900Y17167D01*
X629500Y18100D01*
X629300Y19167D01*
X629500Y20233D01*
X629900Y21167D01*
X630500Y21700D01*
X631100Y21833D01*
X631700Y21700D01*
X632300Y21167D01*
X632700Y20233D01*
X632800Y19167D01*
X632700Y18100D01*
X632300Y17167D01*
X631700Y16633D01*
X631100Y16500D01*
G01X637400D02*
Y21833D01*
G01Y20500D02*
X637800Y21167D01*
X638400Y21700D01*
X639200Y21833D01*
X639900Y21700D01*
X640500Y21167D01*
X640800Y20233D01*
Y16500D01*
G01X655100D02*
X654500Y16633D01*
X653900Y17167D01*
X653500Y18100D01*
X653300Y19167D01*
X653500Y20233D01*
X653900Y21167D01*
X654500Y21700D01*
X655100Y21833D01*
X655700Y21700D01*
X656300Y21167D01*
X656700Y20233D01*
X656800Y19167D01*
X656700Y18100D01*
X656300Y17167D01*
X655700Y16633D01*
X655100Y16500D01*
G01X662500D02*
Y23300D01*
X662700Y23967D01*
X663100Y24367D01*
X663700Y24500D01*
X664300Y24233D01*
X664600Y23567D01*
G01X663400Y21300D02*
X661400D01*
G01X677400Y16500D02*
Y24500D01*
G01Y20633D02*
X677900Y21300D01*
X678400Y21700D01*
X679200Y21833D01*
X679800Y21700D01*
X680500Y21167D01*
X680800Y20367D01*
Y16500D01*
G01X687100D02*
X686500Y16633D01*
X685900Y17167D01*
X685500Y18100D01*
X685300Y19167D01*
X685500Y20233D01*
X685900Y21167D01*
X686500Y21700D01*
X687100Y21833D01*
X687700Y21700D01*
X688300Y21167D01*
X688700Y20233D01*
X688800Y19167D01*
X688700Y18100D01*
X688300Y17167D01*
X687700Y16633D01*
X687100Y16500D01*
G01X695100D02*
Y24500D01*
G01X701600Y20100D02*
X704800D01*
X704500Y21033D01*
X704000Y21567D01*
X703300Y21833D01*
X702600Y21700D01*
X702000Y21300D01*
X701600Y20367D01*
X701400Y19566D01*
Y18767D01*
X701600Y17967D01*
X702100Y17167D01*
X702700Y16633D01*
X703400Y16500D01*
X704100Y16767D01*
X704800Y17566D01*
G01X719100Y24500D02*
Y16500D01*
G01X717700Y21833D02*
X720500D01*
G01X727100Y16500D02*
X726500Y16633D01*
X725900Y17167D01*
X725500Y18100D01*
X725300Y19167D01*
X725500Y20233D01*
X725900Y21167D01*
X726500Y21700D01*
X727100Y21833D01*
X727700Y21700D01*
X728300Y21167D01*
X728700Y20233D01*
X728800Y19167D01*
X728700Y18100D01*
X728300Y17167D01*
X727700Y16633D01*
X727100Y16500D01*
G01X741400D02*
Y24500D01*
G01Y20633D02*
X741900Y21300D01*
X742400Y21700D01*
X743200Y21833D01*
X743800Y21700D01*
X744500Y21167D01*
X744800Y20367D01*
Y16500D01*
G01X751100D02*
X750500Y16633D01*
X749900Y17167D01*
X749500Y18100D01*
X749300Y19167D01*
X749500Y20233D01*
X749900Y21167D01*
X750500Y21700D01*
X751100Y21833D01*
X751700Y21700D01*
X752300Y21167D01*
X752700Y20233D01*
X752800Y19167D01*
X752700Y18100D01*
X752300Y17167D01*
X751700Y16633D01*
X751100Y16500D01*
G01X759100D02*
Y24500D01*
G01X765600Y20100D02*
X768800D01*
X768500Y21033D01*
X768000Y21567D01*
X767300Y21833D01*
X766600Y21700D01*
X766000Y21300D01*
X765600Y20367D01*
X765400Y19566D01*
Y18767D01*
X765600Y17967D01*
X766100Y17167D01*
X766700Y16633D01*
X767400Y16500D01*
X768100Y16767D01*
X768800Y17566D01*
G01X625400Y39000D02*
X627800D01*
G01X626600D02*
Y31000D01*
G01X625400D02*
X627800D01*
G01X634600Y39000D02*
Y31000D01*
G01X633200Y36333D02*
X636000D01*
G01X641100Y34600D02*
X644300D01*
X644000Y35533D01*
X643500Y36067D01*
X642800Y36333D01*
X642100Y36200D01*
X641500Y35800D01*
X641100Y34867D01*
X640900Y34066D01*
Y33267D01*
X641100Y32467D01*
X641600Y31667D01*
X642200Y31133D01*
X642900Y31000D01*
X643600Y31267D01*
X644300Y32066D01*
G01X647600Y31000D02*
Y36333D01*
G01Y34867D02*
X647900Y35533D01*
X648400Y36067D01*
X649100Y36333D01*
X649800Y36067D01*
X650300Y35533D01*
X650600Y34867D01*
Y31000D01*
G01Y34867D02*
X650900Y35533D01*
X651400Y36067D01*
X652100Y36333D01*
X652800Y36067D01*
X653300Y35533D01*
X653600Y34733D01*
Y31000D01*
G01X657100Y31933D02*
X657600Y31400D01*
X658300Y31000D01*
X658900D01*
X659500Y31267D01*
X659900Y31667D01*
X660100Y32200D01*
X660000Y33000D01*
X659600Y33400D01*
X657800Y34200D01*
X657400Y35133D01*
X657600Y35800D01*
X658000Y36200D01*
X658600Y36333D01*
X659200Y36200D01*
X659800Y35800D01*
G01X921200Y-121100D02*
Y-113100D01*
X920000Y-114700D01*
G01Y-121100D02*
X922400D01*
G01X929200Y-121367D02*
X929000Y-121233D01*
Y-120967D01*
X929200Y-120833D01*
X929400Y-120967D01*
Y-121233D01*
X929200Y-121367D01*
G01X937200Y-113100D02*
X936400Y-113367D01*
X935800Y-114033D01*
X935400Y-114833D01*
X935100Y-115900D01*
X935000Y-117100D01*
X935100Y-118300D01*
X935400Y-119367D01*
X935800Y-120167D01*
X936400Y-120833D01*
X937200Y-121100D01*
X938000Y-120833D01*
X938600Y-120167D01*
X939000Y-119367D01*
X939300Y-118300D01*
X939400Y-117100D01*
X939300Y-115900D01*
X939000Y-114833D01*
X938600Y-114033D01*
X938000Y-113367D01*
X937200Y-113100D01*
G01X942200Y-121100D02*
Y-115767D01*
G01Y-117233D02*
X942500Y-116567D01*
X943000Y-116033D01*
X943700Y-115767D01*
X944400Y-116033D01*
X944900Y-116567D01*
X945200Y-117233D01*
Y-121100D01*
G01Y-117233D02*
X945500Y-116567D01*
X946000Y-116033D01*
X946700Y-115767D01*
X947400Y-116033D01*
X947900Y-116567D01*
X948200Y-117367D01*
Y-121100D01*
G01X953200Y-115767D02*
Y-121100D01*
G01Y-113633D02*
X953000Y-113500D01*
Y-113233D01*
X953200Y-113100D01*
X953400Y-113233D01*
Y-113500D01*
X953200Y-113633D01*
G01X961200Y-121100D02*
Y-113100D01*
G01X974200Y-121100D02*
Y-115767D01*
G01Y-117233D02*
X974500Y-116567D01*
X975000Y-116033D01*
X975700Y-115767D01*
X976400Y-116033D01*
X976900Y-116567D01*
X977200Y-117233D01*
Y-121100D01*
G01Y-117233D02*
X977500Y-116567D01*
X978000Y-116033D01*
X978700Y-115767D01*
X979400Y-116033D01*
X979900Y-116567D01*
X980200Y-117367D01*
Y-121100D01*
G01X987000D02*
Y-115767D01*
G01Y-116700D02*
X986600Y-116167D01*
X986000Y-115900D01*
X985300Y-115767D01*
X984600Y-116033D01*
X984000Y-116567D01*
X983600Y-117367D01*
X983400Y-118433D01*
X983600Y-119500D01*
X984000Y-120300D01*
X984600Y-120833D01*
X985300Y-121100D01*
X986000Y-120967D01*
X986600Y-120567D01*
X987000Y-120034D01*
G01X991700Y-115767D02*
X994700Y-121100D01*
G01Y-115767D02*
X991700Y-121100D01*
G01X921837Y-106133D02*
X924237D01*
G01X922937Y-104400D02*
Y-107867D01*
G01X929137Y-109067D02*
X932737Y-100800D01*
G01X937637Y-106133D02*
X940237D01*
G01X944737Y-107600D02*
X945337Y-108267D01*
X946037Y-108667D01*
X946937Y-108800D01*
X947837Y-108533D01*
X948537Y-108000D01*
X949037Y-107067D01*
X949137Y-106000D01*
X948937Y-104933D01*
X948437Y-104267D01*
X947737Y-103733D01*
X947037Y-103600D01*
X946337Y-103733D01*
X945437Y-104267D01*
X945737Y-100800D01*
X948437D01*
G01X951937Y-108800D02*
Y-103467D01*
G01Y-104933D02*
X952237Y-104267D01*
X952737Y-103733D01*
X953437Y-103467D01*
X954137Y-103733D01*
X954637Y-104267D01*
X954937Y-104933D01*
Y-108800D01*
G01Y-104933D02*
X955237Y-104267D01*
X955737Y-103733D01*
X956437Y-103467D01*
X957137Y-103733D01*
X957637Y-104267D01*
X957937Y-105067D01*
Y-108800D01*
G01X962937Y-103467D02*
Y-108800D01*
G01Y-101333D02*
X962737Y-101200D01*
Y-100933D01*
X962937Y-100800D01*
X963137Y-100933D01*
Y-101200D01*
X962937Y-101333D01*
G01X970937Y-108800D02*
Y-100800D01*
G01X921837Y-93133D02*
X924237D01*
G01X922937Y-91400D02*
Y-94867D01*
G01X929137Y-96067D02*
X932737Y-87800D01*
G01X937637Y-93133D02*
X940237D01*
G01X944737Y-94600D02*
X945337Y-95267D01*
X946037Y-95667D01*
X946937Y-95800D01*
X947837Y-95533D01*
X948537Y-95000D01*
X949037Y-94067D01*
X949137Y-93000D01*
X948937Y-91933D01*
X948437Y-91267D01*
X947737Y-90733D01*
X947037Y-90600D01*
X946337Y-90733D01*
X945437Y-91267D01*
X945737Y-87800D01*
X948437D01*
G01X951937Y-95800D02*
Y-90467D01*
G01Y-91933D02*
X952237Y-91267D01*
X952737Y-90733D01*
X953437Y-90467D01*
X954137Y-90733D01*
X954637Y-91267D01*
X954937Y-91933D01*
Y-95800D01*
G01Y-91933D02*
X955237Y-91267D01*
X955737Y-90733D01*
X956437Y-90467D01*
X957137Y-90733D01*
X957637Y-91267D01*
X957937Y-92067D01*
Y-95800D01*
G01X962937Y-90467D02*
Y-95800D01*
G01Y-88333D02*
X962737Y-88200D01*
Y-87933D01*
X962937Y-87800D01*
X963137Y-87933D01*
Y-88200D01*
X962937Y-88333D01*
G01X970937Y-95800D02*
Y-87800D01*
G01X921837Y-80633D02*
X924237D01*
G01X922937Y-78900D02*
Y-82367D01*
G01X929137Y-83567D02*
X932737Y-75300D01*
G01X937637Y-80633D02*
X940237D01*
G01X945037Y-76633D02*
X945637Y-75833D01*
X946337Y-75433D01*
X947137Y-75300D01*
X948137Y-75567D01*
X948837Y-76233D01*
X949037Y-77033D01*
X948937Y-77834D01*
X948537Y-78500D01*
X946537Y-79833D01*
X945637Y-80767D01*
X945037Y-82100D01*
X944837Y-83300D01*
X949037D01*
G01X951937D02*
Y-77967D01*
G01Y-79433D02*
X952237Y-78767D01*
X952737Y-78233D01*
X953437Y-77967D01*
X954137Y-78233D01*
X954637Y-78767D01*
X954937Y-79433D01*
Y-83300D01*
G01Y-79433D02*
X955237Y-78767D01*
X955737Y-78233D01*
X956437Y-77967D01*
X957137Y-78233D01*
X957637Y-78767D01*
X957937Y-79567D01*
Y-83300D01*
G01X962937Y-77967D02*
Y-83300D01*
G01Y-75833D02*
X962737Y-75700D01*
Y-75433D01*
X962937Y-75300D01*
X963137Y-75433D01*
Y-75700D01*
X962937Y-75833D01*
G01X970937Y-83300D02*
Y-75300D01*
G01X921620Y-68433D02*
X924020D01*
G01X922720Y-66700D02*
Y-70167D01*
G01X928520Y-69500D02*
X929120Y-70433D01*
X929920Y-70967D01*
X930820Y-71100D01*
X931620Y-70967D01*
X932420Y-70300D01*
X932920Y-69500D01*
X933020Y-68700D01*
X932820Y-67767D01*
X932120Y-67100D01*
X931420Y-66833D01*
X930520D01*
G01X931420D02*
X932020Y-66433D01*
X932520Y-65767D01*
X932720Y-64967D01*
X932520Y-64167D01*
X932020Y-63500D01*
X931120Y-63100D01*
X930220Y-63233D01*
X929320Y-63767D01*
G01X936920Y-71367D02*
X940520Y-63100D01*
G01X945420Y-68433D02*
X948020D01*
G01X954720Y-63100D02*
X953920Y-63367D01*
X953320Y-64033D01*
X952920Y-64833D01*
X952620Y-65900D01*
X952520Y-67100D01*
X952620Y-68300D01*
X952920Y-69367D01*
X953320Y-70167D01*
X953920Y-70833D01*
X954720Y-71100D01*
X955520Y-70833D01*
X956120Y-70167D01*
X956520Y-69367D01*
X956820Y-68300D01*
X956920Y-67100D01*
X956820Y-65900D01*
X956520Y-64833D01*
X956120Y-64033D01*
X955520Y-63367D01*
X954720Y-63100D01*
G01X959720Y-71100D02*
Y-65767D01*
G01Y-67233D02*
X960020Y-66567D01*
X960520Y-66033D01*
X961220Y-65767D01*
X961920Y-66033D01*
X962420Y-66567D01*
X962720Y-67233D01*
Y-71100D01*
G01Y-67233D02*
X963020Y-66567D01*
X963520Y-66033D01*
X964220Y-65767D01*
X964920Y-66033D01*
X965420Y-66567D01*
X965720Y-67367D01*
Y-71100D01*
G01X970720Y-65767D02*
Y-71100D01*
G01Y-63633D02*
X970520Y-63500D01*
Y-63233D01*
X970720Y-63100D01*
X970920Y-63233D01*
Y-63500D01*
X970720Y-63633D01*
G01X978720Y-71100D02*
Y-63100D01*
G01X921837Y-56133D02*
X924237D01*
G01X922937Y-54400D02*
Y-57867D01*
G01X929137Y-59067D02*
X932737Y-50800D01*
G01X937637Y-56133D02*
X940237D01*
G01X945037Y-52133D02*
X945637Y-51333D01*
X946337Y-50933D01*
X947137Y-50800D01*
X948137Y-51067D01*
X948837Y-51733D01*
X949037Y-52533D01*
X948937Y-53334D01*
X948537Y-54000D01*
X946537Y-55333D01*
X945637Y-56267D01*
X945037Y-57600D01*
X944837Y-58800D01*
X949037D01*
G01X951937D02*
Y-53467D01*
G01Y-54933D02*
X952237Y-54267D01*
X952737Y-53733D01*
X953437Y-53467D01*
X954137Y-53733D01*
X954637Y-54267D01*
X954937Y-54933D01*
Y-58800D01*
G01Y-54933D02*
X955237Y-54267D01*
X955737Y-53733D01*
X956437Y-53467D01*
X957137Y-53733D01*
X957637Y-54267D01*
X957937Y-55067D01*
Y-58800D01*
G01X962937Y-53467D02*
Y-58800D01*
G01Y-51333D02*
X962737Y-51200D01*
Y-50933D01*
X962937Y-50800D01*
X963137Y-50933D01*
Y-51200D01*
X962937Y-51333D01*
G01X970937Y-58800D02*
Y-50800D01*
G01X921837Y-43572D02*
X924237D01*
G01X922937Y-41839D02*
Y-45306D01*
G01X929137Y-46506D02*
X932737Y-38239D01*
G01X937637Y-43572D02*
X940237D01*
G01X944737Y-44639D02*
X945337Y-45572D01*
X946137Y-46106D01*
X947037Y-46239D01*
X947837Y-46106D01*
X948637Y-45439D01*
X949137Y-44639D01*
X949237Y-43839D01*
X949037Y-42906D01*
X948337Y-42239D01*
X947637Y-41972D01*
X946737D01*
G01X947637D02*
X948237Y-41572D01*
X948737Y-40906D01*
X948937Y-40106D01*
X948737Y-39306D01*
X948237Y-38639D01*
X947337Y-38239D01*
X946437Y-38372D01*
X945537Y-38906D01*
G01X951937Y-46239D02*
Y-40906D01*
G01Y-42372D02*
X952237Y-41706D01*
X952737Y-41172D01*
X953437Y-40906D01*
X954137Y-41172D01*
X954637Y-41706D01*
X954937Y-42372D01*
Y-46239D01*
G01Y-42372D02*
X955237Y-41706D01*
X955737Y-41172D01*
X956437Y-40906D01*
X957137Y-41172D01*
X957637Y-41706D01*
X957937Y-42506D01*
Y-46239D01*
G01X962937Y-40906D02*
Y-46239D01*
G01Y-38772D02*
X962737Y-38639D01*
Y-38372D01*
X962937Y-38239D01*
X963137Y-38372D01*
Y-38639D01*
X962937Y-38772D01*
G01X970937Y-46239D02*
Y-38239D01*
G01X920200Y-30833D02*
X922600D01*
G01X921300Y-29100D02*
Y-32567D01*
G01X927500Y-33767D02*
X931100Y-25500D01*
G01X936000Y-30833D02*
X938600D01*
G01X943400Y-26833D02*
X944000Y-26033D01*
X944700Y-25633D01*
X945500Y-25500D01*
X946500Y-25767D01*
X947200Y-26433D01*
X947400Y-27233D01*
X947300Y-28034D01*
X946900Y-28700D01*
X944900Y-30033D01*
X944000Y-30967D01*
X943400Y-32300D01*
X943200Y-33500D01*
X947400D01*
G01X950300D02*
Y-28167D01*
G01Y-29633D02*
X950600Y-28967D01*
X951100Y-28433D01*
X951800Y-28167D01*
X952500Y-28433D01*
X953000Y-28967D01*
X953300Y-29633D01*
Y-33500D01*
G01Y-29633D02*
X953600Y-28967D01*
X954100Y-28433D01*
X954800Y-28167D01*
X955500Y-28433D01*
X956000Y-28967D01*
X956300Y-29767D01*
Y-33500D01*
G01X961300Y-28167D02*
Y-33500D01*
G01Y-26033D02*
X961100Y-25900D01*
Y-25633D01*
X961300Y-25500D01*
X961500Y-25633D01*
Y-25900D01*
X961300Y-26033D01*
G01X969300Y-33500D02*
Y-25500D01*
G01X921837Y-17633D02*
X924237D01*
G01X922937Y-15900D02*
Y-19367D01*
G01X930937Y-20300D02*
Y-12300D01*
X929737Y-13900D01*
G01Y-20300D02*
X932137D01*
G01X937137Y-20567D02*
X940737Y-12300D01*
G01X945637Y-17633D02*
X948237D01*
G01X952737Y-18700D02*
X953337Y-19633D01*
X954137Y-20167D01*
X955037Y-20300D01*
X955837Y-20167D01*
X956637Y-19500D01*
X957137Y-18700D01*
X957237Y-17900D01*
X957037Y-16967D01*
X956337Y-16300D01*
X955637Y-16033D01*
X954737D01*
G01X955637D02*
X956237Y-15633D01*
X956737Y-14967D01*
X956937Y-14167D01*
X956737Y-13367D01*
X956237Y-12700D01*
X955337Y-12300D01*
X954437Y-12433D01*
X953537Y-12967D01*
G01X959937Y-20300D02*
Y-14967D01*
G01Y-16433D02*
X960237Y-15767D01*
X960737Y-15233D01*
X961437Y-14967D01*
X962137Y-15233D01*
X962637Y-15767D01*
X962937Y-16433D01*
Y-20300D01*
G01Y-16433D02*
X963237Y-15767D01*
X963737Y-15233D01*
X964437Y-14967D01*
X965137Y-15233D01*
X965637Y-15767D01*
X965937Y-16567D01*
Y-20300D01*
G01X970937Y-14967D02*
Y-20300D01*
G01Y-12833D02*
X970737Y-12700D01*
Y-12433D01*
X970937Y-12300D01*
X971137Y-12433D01*
Y-12700D01*
X970937Y-12833D01*
G01X978937Y-20300D02*
Y-12300D01*
G01X921837Y-5633D02*
X924237D01*
G01X922937Y-3900D02*
Y-7367D01*
G01X929137Y-8567D02*
X932737Y-300D01*
G01X937637Y-5633D02*
X940237D01*
G01X945037Y-1633D02*
X945637Y-833D01*
X946337Y-433D01*
X947137Y-300D01*
X948137Y-567D01*
X948837Y-1233D01*
X949037Y-2033D01*
X948937Y-2834D01*
X948537Y-3500D01*
X946537Y-4833D01*
X945637Y-5767D01*
X945037Y-7100D01*
X944837Y-8300D01*
X949037D01*
G01X951937D02*
Y-2967D01*
G01Y-4433D02*
X952237Y-3767D01*
X952737Y-3233D01*
X953437Y-2967D01*
X954137Y-3233D01*
X954637Y-3767D01*
X954937Y-4433D01*
Y-8300D01*
G01Y-4433D02*
X955237Y-3767D01*
X955737Y-3233D01*
X956437Y-2967D01*
X957137Y-3233D01*
X957637Y-3767D01*
X957937Y-4567D01*
Y-8300D01*
G01X962937Y-2967D02*
Y-8300D01*
G01Y-833D02*
X962737Y-700D01*
Y-433D01*
X962937Y-300D01*
X963137Y-433D01*
Y-700D01*
X962937Y-833D01*
G01X970937Y-8300D02*
Y-300D01*
G01X921837Y6867D02*
X924237D01*
G01X922937Y8600D02*
Y5133D01*
G01X929037Y10867D02*
X929637Y11667D01*
X930337Y12067D01*
X931137Y12200D01*
X932137Y11933D01*
X932837Y11267D01*
X933037Y10467D01*
X932937Y9666D01*
X932537Y9000D01*
X930537Y7667D01*
X929637Y6733D01*
X929037Y5400D01*
X928837Y4200D01*
X933037D01*
G01X937137Y3933D02*
X940737Y12200D01*
G01X945637Y6867D02*
X948237D01*
G01X956137Y4200D02*
Y12200D01*
X952437Y6467D01*
X957437D01*
G01X959937Y4200D02*
Y9533D01*
G01Y8067D02*
X960237Y8733D01*
X960737Y9267D01*
X961437Y9533D01*
X962137Y9267D01*
X962637Y8733D01*
X962937Y8067D01*
Y4200D01*
G01Y8067D02*
X963237Y8733D01*
X963737Y9267D01*
X964437Y9533D01*
X965137Y9267D01*
X965637Y8733D01*
X965937Y7933D01*
Y4200D01*
G01X970937Y9533D02*
Y4200D01*
G01Y11667D02*
X970737Y11800D01*
Y12067D01*
X970937Y12200D01*
X971137Y12067D01*
Y11800D01*
X970937Y11667D01*
G01X978937Y4200D02*
Y12200D01*
G01X921837Y19367D02*
X924237D01*
G01X922937Y21100D02*
Y17633D01*
G01X929137Y16433D02*
X932737Y24700D01*
G01X937637Y19367D02*
X940237D01*
G01X944737Y18300D02*
X945337Y17367D01*
X946137Y16833D01*
X947037Y16700D01*
X947837Y16833D01*
X948637Y17500D01*
X949137Y18300D01*
X949237Y19100D01*
X949037Y20033D01*
X948337Y20700D01*
X947637Y20967D01*
X946737D01*
G01X947637D02*
X948237Y21367D01*
X948737Y22033D01*
X948937Y22833D01*
X948737Y23633D01*
X948237Y24300D01*
X947337Y24700D01*
X946437Y24567D01*
X945537Y24033D01*
G01X951937Y16700D02*
Y22033D01*
G01Y20567D02*
X952237Y21233D01*
X952737Y21767D01*
X953437Y22033D01*
X954137Y21767D01*
X954637Y21233D01*
X954937Y20567D01*
Y16700D01*
G01Y20567D02*
X955237Y21233D01*
X955737Y21767D01*
X956437Y22033D01*
X957137Y21767D01*
X957637Y21233D01*
X957937Y20433D01*
Y16700D01*
G01X962937Y22033D02*
Y16700D01*
G01Y24167D02*
X962737Y24300D01*
Y24567D01*
X962937Y24700D01*
X963137Y24567D01*
Y24300D01*
X962937Y24167D01*
G01X970937Y16700D02*
Y24700D01*
G01X923000Y39500D02*
Y31500D01*
G01X920700Y39500D02*
X925300D01*
G01X931000Y31500D02*
X930400Y31633D01*
X929800Y32167D01*
X929400Y33100D01*
X929200Y34167D01*
X929400Y35233D01*
X929800Y36167D01*
X930400Y36700D01*
X931000Y36833D01*
X931600Y36700D01*
X932200Y36167D01*
X932600Y35233D01*
X932700Y34167D01*
X932600Y33100D01*
X932200Y32167D01*
X931600Y31633D01*
X931000Y31500D01*
G01X939000D02*
Y39500D01*
G01X945500Y35100D02*
X948700D01*
X948400Y36033D01*
X947900Y36567D01*
X947200Y36833D01*
X946500Y36700D01*
X945900Y36300D01*
X945500Y35367D01*
X945300Y34566D01*
Y33767D01*
X945500Y32967D01*
X946000Y32167D01*
X946600Y31633D01*
X947300Y31500D01*
X948000Y31767D01*
X948700Y32566D01*
G01X953600Y31500D02*
Y36833D01*
G01Y35767D02*
X954100Y36300D01*
X954600Y36700D01*
X955300Y36833D01*
X955800Y36700D01*
X956400Y36300D01*
G01X964800Y31500D02*
Y36833D01*
G01Y35900D02*
X964400Y36433D01*
X963800Y36700D01*
X963100Y36833D01*
X962400Y36567D01*
X961800Y36033D01*
X961400Y35233D01*
X961200Y34167D01*
X961400Y33100D01*
X961800Y32300D01*
X962400Y31767D01*
X963100Y31500D01*
X963800Y31633D01*
X964400Y32033D01*
X964800Y32566D01*
G01X969300Y31500D02*
Y36833D01*
G01Y35500D02*
X969700Y36167D01*
X970300Y36700D01*
X971100Y36833D01*
X971800Y36700D01*
X972400Y36167D01*
X972700Y35233D01*
Y31500D01*
G01X980600Y36167D02*
X979900Y36700D01*
X979300Y36833D01*
X978500Y36567D01*
X977900Y36033D01*
X977500Y35100D01*
X977400Y34167D01*
X977500Y33233D01*
X977900Y32433D01*
X978500Y31767D01*
X979300Y31500D01*
X980000Y31767D01*
X980600Y32300D01*
G01X985500Y35100D02*
X988700D01*
X988400Y36033D01*
X987900Y36567D01*
X987200Y36833D01*
X986500Y36700D01*
X985900Y36300D01*
X985500Y35367D01*
X985300Y34566D01*
Y33767D01*
X985500Y32967D01*
X986000Y32167D01*
X986600Y31633D01*
X987300Y31500D01*
X988000Y31767D01*
X988700Y32566D01*
G01X-346700Y605700D02*
Y-263100D01*
X1194200D01*
Y605700D01*
X-346700D01*
G01Y187300D02*
X1194200D01*
G01X-123200Y-4700D02*
X-183000D01*
X-183100Y-4600D01*
G01X-123300Y34800D02*
X-183200D01*
G01X-161200Y-25900D02*
Y-4700D01*
X-161300Y-4600D01*
X-165700Y-9000D01*
G01X-161000Y-4800D02*
Y-4900D01*
X-156900Y-9000D01*
G01X-160200Y34800D02*
X-160100D01*
X-157000Y37900D01*
G01X-160200Y35200D02*
X-159800D01*
G01X-160100Y55100D02*
Y35300D01*
X-160400Y35000D01*
X-163400Y38000D01*
G01X-164627Y440097D02*
X-164617Y428097D01*
G01X-164627Y440097D02*
X-140606Y416117D01*
X-140600Y376800D01*
G01X-164627Y440097D02*
X-152627Y440107D01*
G01X-147700Y-63400D02*
X-123100D01*
X-122900Y-63200D01*
X-125300Y-60800D01*
G01X-135200Y-90200D02*
X-96300D01*
X-96000Y-89900D01*
X-98600Y-87300D01*
G01X-123100Y-63200D02*
Y-63500D01*
X-125000Y-65400D01*
G01X-122900Y-20800D02*
Y-70000D01*
X-123000Y-70100D01*
G01X-122900Y53900D02*
Y125900D01*
G01X-122600Y108700D02*
Y108600D01*
X-120800Y106800D01*
G01X-109100Y108700D02*
X-122500D01*
X-122700Y108900D01*
X-120600Y111000D01*
G01X-116800Y-63300D02*
Y-63500D01*
X-114300Y-66000D01*
G01X-116900Y-20600D02*
Y-69600D01*
X-117000Y-69700D01*
G01X-101500Y-63400D02*
X-116700D01*
X-116800Y-63300D01*
X-114200Y-60700D01*
G01X-107180Y421270D02*
X-65180D01*
G01X-107180D02*
X-99180Y413270D01*
G01X-107180Y421270D02*
X-99180Y429270D01*
G01X-118720Y447840D02*
X-94720Y471840D01*
X-62720D01*
G01X-118720Y447840D02*
Y459840D01*
G01Y447840D02*
X-106720D01*
G01X-96000Y-57800D02*
Y-105400D01*
G01X-96100Y-90200D02*
X-96300D01*
X-98900Y-92800D01*
G01X-71000Y-57300D02*
Y-105300D01*
G01X-70900Y-89800D02*
Y-89900D01*
X-67700Y-93100D01*
G01X-39700Y-89900D02*
X-70800D01*
X-71000Y-89700D01*
X-68000Y-86700D01*
G01X-71000Y-57800D02*
X23400D01*
X24000Y-58400D01*
G01X-72000Y88400D02*
X17300D01*
X17800Y88900D01*
G01X-64800Y108900D02*
X-43900D01*
X-43700Y109100D01*
X-46500Y111900D01*
X-46600D01*
G01X-43800Y109000D02*
Y108900D01*
X-46400Y106300D01*
G01X-43800Y50800D02*
Y123300D01*
X-43700Y123400D01*
G01X-18000Y-57300D02*
X-17800D01*
X-14200Y-53700D01*
G01X-18100Y-57400D02*
X-18600D01*
X-22500Y-53500D01*
G01X-18200Y-3500D02*
Y-57200D01*
X-18800Y-57800D01*
G01X-19300Y87800D02*
Y36600D01*
X-18800Y36100D01*
G01X-19300Y88200D02*
X-16100Y85000D01*
G01X-19400Y88300D02*
X-22800Y84900D01*
G01X296500Y605800D02*
Y-263100D01*
G01X319600Y44000D02*
Y-123500D01*
G01D02*
X915300D01*
Y44000D01*
X999100D01*
Y26500D01*
G01X915300Y-123500D02*
X999100D01*
Y-111000D01*
X319600D01*
G01Y-86000D02*
Y-98500D01*
G01Y-86000D02*
Y-98500D01*
G01D02*
X347600D01*
G01X319600Y-86000D02*
X347600D01*
G01X319600Y-61000D02*
Y-73500D01*
G01D02*
X347600D01*
G01X319600Y-48500D02*
Y-61000D01*
G01D02*
X347600D01*
G01X319600Y-36000D02*
Y-48500D01*
G01D02*
X347600D01*
G01X319600Y-36000D02*
Y-48500D01*
G01D02*
X347600D01*
G01X319600Y-36000D02*
X347600D01*
G01X319600Y-23500D02*
X347600D01*
G01X319600Y1500D02*
Y-11000D01*
G01D02*
X347600D01*
G01X319600Y14000D02*
Y1500D01*
G01D02*
X347600D01*
G01X319600Y26500D02*
Y14000D01*
G01D02*
X347600D01*
G01X972600Y26500D02*
X319600D01*
G01D02*
Y44000D01*
G01Y26500D02*
X999100D01*
Y14000D01*
G01X319600Y44000D02*
X328600D01*
G01X975750D02*
X319600D01*
G01X328600D02*
X915300D01*
G01X347600Y-123500D02*
Y1500D01*
G01D02*
Y14000D01*
G01D02*
X461600D01*
G01X347600D02*
Y26500D01*
G01D02*
Y44000D01*
G01X461600Y-123500D02*
Y27000D01*
G01X975750Y-98500D02*
X461600D01*
G01X975750Y-86000D02*
X461600D01*
G01Y-73500D02*
X999100D01*
Y-86000D01*
G01X975750Y-61000D02*
X461600D01*
G01X975750Y-48500D02*
X461600D01*
G01X975750D02*
X461600D01*
G01Y-36000D02*
X999100D01*
Y-48500D01*
G01X975750Y-23500D02*
X461600D01*
G01Y-11000D02*
X999100D01*
Y-23500D01*
G01X975750Y1500D02*
X461600D01*
G01X975750Y14000D02*
X461600D01*
G01D02*
Y26500D01*
G01D02*
Y44000D01*
G01X884250Y-98500D02*
X999100D01*
Y-111000D01*
G01X884250Y-86000D02*
X999100D01*
Y-98500D01*
G01X884250Y-61000D02*
X999100D01*
Y-73500D01*
G01X884250Y-48500D02*
X975750D01*
G01X884250D02*
X999100D01*
Y-61000D01*
G01X884250Y-23500D02*
X999100D01*
Y-36000D01*
G01X884250Y1500D02*
X999100D01*
Y-11000D01*
G01X884250Y14000D02*
X999100D01*
Y1500D01*
G01X915400Y-133600D02*
X915300Y-133500D01*
G01X954400Y187300D02*
Y187400D01*
M02*
